G04 ================== begin FILE IDENTIFICATION RECORD ==================*
G04 Layout Name:  15669-1.brd*
G04 Film Name:    L8*
G04 File Format:  Gerber RS274X*
G04 File Origin:  Cadence Allegro 16.5-S056*
G04 Origin Date:  Wed Nov 16 04:09:02 2016*
G04 *
G04 Layer:  VIA CLASS/BOTTOM*
G04 Layer:  PIN/BOTTOM*
G04 Layer:  ETCH/BOTTOM*
G04 Layer:  DRAWING FORMAT/LAYER_PCB_STORY*
G04 Layer:  DRAWING FORMAT/LAYER_L8*
G04 *
G04 Offset:    (0.00 0.00)*
G04 Mirror:    No*
G04 Mode:      Positive*
G04 Rotation:  0*
G04 FullContactRelief:  No*
G04 UndefLineWidth:     6.00*
G04 ================== end FILE IDENTIFICATION RECORD ====================*
%FSLAX35Y35*MOIN*%
%IR0*IPPOS*OFA0.00000B0.00000*MIA0B0*SFA1.00000B1.00000*%
%ADD17O,.103X.06*%
%ADD21R,.23X.032*%
%AMMACRO18*
4,1,8,.197,-.186,
-.197,-.186,
-.197,.186,
.197,.186,
.197,.00925,
-.059,.00925,
-.059,-.00925,
.197,-.00925,
.197,-.186,
0.0*
%
%ADD18MACRO18*%
%ADD10C,.01*%
%ADD12C,.02*%
%ADD11C,.04*%
%ADD13C,.034*%
%ADD15C,.028*%
%ADD20R,.001X.001*%
%ADD16C,.315*%
%ADD14R,.098X.02*%
%ADD19R,.394X.172*%
%ADD22C,.032*%
%ADD23C,.006*%
%ADD24C,.00675*%
%ADD25C,.00688*%
%ADD30O,.12702X.08402*%
%ADD28C,.05204*%
%ADD26C,.04404*%
%ADD33C,.09204*%
%ADD32C,.09704*%
%ADD34C,.11004*%
%ADD27C,.11104*%
%ADD36C,.17004*%
%ADD35O,.315X.4528*%
%ADD29C,.33904*%
%ADD31O,.315X.45279*%
G75*
%LPD*%
G75*
G36*
G01X57019Y294513D02*
G03Y290585I-995J-1964D01*
G02X57600Y290228I181J-357D01*
G01Y282200D01*
X71719Y268081D01*
X71730Y268065D01*
G03X72465Y267330I2170J1435D01*
G01X72481Y267319D01*
X87557Y252243D01*
Y245129D01*
X77178Y234750D01*
Y223408D01*
X54900Y201130D01*
Y53000D01*
X65850Y42050D01*
Y14250D01*
X67600Y12500D01*
X77100D01*
X82300Y17700D01*
X97900D01*
X100800Y20600D01*
Y25600D01*
X101600Y26400D01*
X117600D01*
X124000Y32800D01*
X132000D01*
Y31403D01*
X126390D01*
X117767Y22780D01*
Y9480D01*
X119247Y8000D01*
X119262D01*
Y3004D01*
X3937D01*
G02X3004Y3937I0J933D01*
G01Y555652D01*
X8000D01*
Y555500D01*
X16500D01*
X20960Y551040D01*
Y359179D01*
X21000Y359140D01*
Y355600D01*
X57600Y319000D01*
Y294870D01*
G02X57019Y294513I-400J0D01*
G37*
G36*
G01X69460Y1046362D02*
X70500Y1045323D01*
Y1029500D01*
X50500Y1009500D01*
Y934800D01*
X63700Y921600D01*
Y913700D01*
X55000Y905000D01*
X50500D01*
X27000Y928500D01*
X14000D01*
X3001Y939499D01*
Y1078001D01*
X8000Y1083000D01*
X48800D01*
X69460Y1062340D01*
Y1046362D01*
G37*
G36*
G01X148780Y3004D02*
Y8358D01*
X148745D01*
Y8765D01*
X148300Y9210D01*
Y23826D01*
X140723Y31403D01*
X133500D01*
Y32800D01*
X144400D01*
X160300Y16900D01*
X210217D01*
X215887Y22570D01*
Y29130D01*
X209465Y35552D01*
X206651D01*
X196638Y25540D01*
X164460D01*
X153600Y36400D01*
Y39654D01*
G03X153957Y39943I-1199J1846D01*
G01X167812Y53798D01*
X283912D01*
X313312Y83198D01*
X377388D01*
X380643Y79943D01*
G03X383757Y83057I1557J1557D01*
G01X379212Y87602D01*
X311488D01*
X282088Y58202D01*
X165988D01*
X154987Y47200D01*
X150528D01*
X140126Y57602D01*
X133598D01*
X133100Y58100D01*
X123800D01*
X122100Y56400D01*
Y53400D01*
X120500Y51800D01*
X113300D01*
X110450Y48950D01*
X90627D01*
X88138Y51440D01*
X67438D01*
X59027Y59850D01*
X59110Y112085D01*
X60787Y113762D01*
X72762D01*
X85000Y126000D01*
X125500D01*
X127500Y128000D01*
Y132500D01*
X126000Y134000D01*
X121000D01*
X119500Y132500D01*
X74359D01*
X72859Y134000D01*
X64000D01*
X61000Y137000D01*
Y196779D01*
X90049Y225828D01*
X92887D01*
X92986Y225728D01*
Y218775D01*
X95668Y216094D01*
X100810D01*
X106072Y210832D01*
Y202549D01*
X113040Y195581D01*
Y139349D01*
G03X116118I1539J-1574D01*
G01Y194416D01*
G02X116801Y194699I400J0D01*
G01X145000Y166500D01*
X145519D01*
X146758Y165260D01*
X193662D01*
X195562Y163360D01*
X196239D01*
G02X196633Y162890I0J-400D01*
G03X197694Y160596I2167J-390D01*
G02Y159904I-201J-346D01*
G03X199906I1106J-1904D01*
G02Y160596I201J346D01*
G03X200967Y162890I-1106J1904D01*
G02X201361Y163360I394J70D01*
G01X202138D01*
X204038Y165260D01*
X291194D01*
G03X294719Y166355I1406J1695D01*
G01X294760Y166500D01*
X781500D01*
X803000Y145000D01*
X886700D01*
X931000Y189300D01*
Y249000D01*
X910000Y270000D01*
Y356429D01*
X891266Y375163D01*
X814222D01*
X808889Y380496D01*
X806506D01*
X805086Y379076D01*
Y374310D01*
X812456Y366940D01*
X814534D01*
X816639Y369045D01*
X823328D01*
X832273Y360100D01*
X848600D01*
X860000Y371500D01*
X886228D01*
X891500Y366228D01*
Y350000D01*
X905960Y335540D01*
Y270160D01*
X895000Y259200D01*
Y242500D01*
X904500Y233000D01*
X917000D01*
X922100Y227900D01*
Y193600D01*
X898650Y170150D01*
X887650D01*
X873300Y155800D01*
X809700D01*
X788000Y177500D01*
X177600D01*
G02X177235Y178065I-1J400D01*
G03X173410Y184004I-3825J1738D01*
G01X169110D01*
G03X165285Y178065I0J-4201D01*
G02X164920Y177500I-364J-165D01*
G01X151779D01*
X121100Y208179D01*
Y215676D01*
X120540Y216236D01*
Y219659D01*
X104810Y235388D01*
Y260367D01*
X77000Y288177D01*
Y325400D01*
X41100Y361300D01*
Y762600D01*
X43500Y765000D01*
X45823D01*
X85362Y725460D01*
X147840D01*
X160600Y712700D01*
Y677900D01*
X130600Y647900D01*
Y616800D01*
X131460Y615940D01*
Y615937D01*
X139500Y607898D01*
Y590100D01*
X139986Y589614D01*
Y589612D01*
X149310Y580287D01*
Y575924D01*
G03X150116Y572274I1540J-1574D01*
G01X150249Y572227D01*
Y551893D01*
X151960Y550182D01*
Y548362D01*
X155547Y544776D01*
X155549Y544696D01*
G03X156120Y543269I2201J53D01*
G02Y542731I-296J-269D01*
G03X159380I1630J-1481D01*
G02Y543269I296J269D01*
G03X157804Y546951I-1630J1481D01*
G01X157724Y546953D01*
X155040Y549638D01*
Y550040D01*
X156900Y551900D01*
Y572300D01*
G03Y575700I-1400J1700D01*
G01Y580460D01*
X155040Y582320D01*
Y582330D01*
X147300Y590069D01*
Y645415D01*
G02X147746Y645813I400J1D01*
G03Y650187I254J2187D01*
G02X147300Y650585I-46J397D01*
G01Y652023D01*
X149902Y654625D01*
X162590D01*
X164215Y653000D01*
X172910D01*
G03X173090I90J2200D01*
G01X174000D01*
X175637Y654637D01*
Y660167D01*
X170210Y665594D01*
Y712021D01*
G02X170761Y712391I400J0D01*
G03X169784Y715682I834J2038D01*
G02X169173Y715627I-329J228D01*
G01X157000Y727800D01*
Y744213D01*
G02X157751Y744405I400J0D01*
G03Y749059I4257J2327D01*
G02X157000Y749251I-351J192D01*
G01Y776500D01*
X148000Y785500D01*
X94000D01*
X82600Y796900D01*
Y800200D01*
X86000Y803600D01*
X144300D01*
X146700Y806000D01*
Y809000D01*
X145600Y810100D01*
X142700D01*
X141500Y808900D01*
X74100D01*
X55600Y827400D01*
Y897000D01*
X75800Y917200D01*
Y931100D01*
X81700Y937000D01*
X169000D01*
X170000Y938000D01*
Y944500D01*
X169500Y945000D01*
X166000D01*
X164500Y946500D01*
Y953500D01*
X167500Y956500D01*
Y963938D01*
X197326D01*
G03X200297Y967179I1574J1539D01*
G02Y967798I253J309D01*
G03X200006Y971404I-1397J1702D01*
G02Y972096I201J346D01*
G03Y975904I-1106J1904D01*
G02Y976596I201J346D01*
G03X197794I-1106J1904D01*
G02Y975904I-201J-346D01*
G03Y972096I1106J-1904D01*
G02Y971404I-201J-346D01*
G03X197503Y967798I1106J-1904D01*
G02Y967179I-253J-310D01*
G03X197326Y967016I1401J-1699D01*
G01X165484D01*
X142300Y990200D01*
Y1031500D01*
X134500Y1039300D01*
Y1041278D01*
X134507Y1041304D01*
G03Y1042696I-2507J696D01*
G01X134500Y1042722D01*
Y1055022D01*
X134472Y1055050D01*
Y1058753D01*
X137647Y1061928D01*
X150478D01*
X152595Y1059811D01*
X166011D01*
X172500Y1053322D01*
Y1046000D01*
X174500Y1044000D01*
X189000D01*
X193000Y1048000D01*
Y1054000D01*
X176500Y1070500D01*
X126200D01*
X40500Y1156200D01*
Y1221000D01*
X45000Y1225500D01*
X54500D01*
X82700Y1197300D01*
Y1180300D01*
X83700Y1179300D01*
X86600D01*
X87700Y1180400D01*
Y1201300D01*
X42000Y1247000D01*
X27500D01*
X22500Y1252000D01*
Y1299000D01*
X24500Y1301000D01*
X29000D01*
X31000Y1299000D01*
X54597D01*
X64097Y1308500D01*
X75500D01*
X77850Y1306150D01*
Y1290350D01*
X70000Y1282500D01*
Y1277500D01*
X70372Y1277128D01*
X70387Y1277079D01*
G03X71882Y1275584I2113J618D01*
G01X71931Y1275569D01*
X72000Y1275500D01*
X72358D01*
G03X72642I142J2197D01*
G01X75500D01*
X84500Y1284500D01*
Y1335500D01*
X91500Y1342500D01*
X131000D01*
X132000Y1343500D01*
Y1349500D01*
X131000Y1350500D01*
X100000D01*
X99000Y1349500D01*
X70500D01*
X69500Y1350500D01*
X64000D01*
X61040Y1353460D01*
Y1409493D01*
X87924Y1436377D01*
Y1449905D01*
X85914Y1451914D01*
X87000Y1453000D01*
X101400D01*
X156600Y1397800D01*
Y1360000D01*
X150100Y1353500D01*
Y1350000D01*
X151600Y1348500D01*
X155553D01*
G02X155836Y1347817I0J-400D01*
G01X154735Y1346716D01*
X154655Y1346714D01*
G03X156910Y1344459I54J-2201D01*
G01X156912Y1344539D01*
X159790Y1347416D01*
Y1351190D01*
X169900Y1361300D01*
Y1369300D01*
X166500Y1372700D01*
Y1392303D01*
G02X167092Y1392654I400J0D01*
G03X169110Y1392138I2017J3685D01*
G01X173410D01*
G03Y1400540I0J4201D01*
G01X169110D01*
G03X165257Y1398015I0J-4202D01*
G02X164608Y1397892I-366J160D01*
G01X124939Y1437561D01*
Y1455010D01*
X136529Y1466600D01*
X147628D01*
X147648Y1466596D01*
G03X148542I447J2156D01*
G01X148562Y1466600D01*
X169500D01*
X172100Y1464000D01*
X174900D01*
X175900Y1465000D01*
Y1467400D01*
X172500Y1470800D01*
X148905D01*
X148871Y1470813D01*
G03X147319I-776J-2061D01*
G01X147285Y1470800D01*
X133569D01*
X131744Y1468975D01*
X129625D01*
X129202Y1469398D01*
Y1476702D01*
X131500Y1479000D01*
Y1508000D01*
X129500Y1510000D01*
X126500D01*
X125000Y1508500D01*
Y1483500D01*
X122700Y1481200D01*
Y1466200D01*
X120900Y1464400D01*
X78222D01*
G03X75278I-1472J-1638D01*
G01X68158D01*
Y1471334D01*
X69339Y1472516D01*
X69419Y1472518D01*
G03X67164Y1474773I-54J2201D01*
G01X67162Y1474693D01*
X65078Y1472610D01*
Y1461578D01*
X25000Y1421500D01*
X7500D01*
X5500Y1423500D01*
Y1512500D01*
X6637D01*
X6665Y1512491D01*
G03X7358Y1512386I694J2241D01*
G01X15965D01*
X16125Y1512546D01*
X17743D01*
Y1512288D01*
X19840Y1510191D01*
X36662D01*
X38120Y1511649D01*
X38149D01*
X38171Y1511671D01*
X48178D01*
X49789Y1513282D01*
Y1528475D01*
X48376Y1529888D01*
X40403D01*
X39500Y1530791D01*
Y1558615D01*
X65285Y1584400D01*
X79370D01*
X79800Y1583970D01*
Y1572224D01*
X79672Y1572174D01*
G03Y1568066I793J-2054D01*
G01X79800Y1568016D01*
Y1567799D01*
G02X79161Y1567478I-400J0D01*
G03Y1563304I-1554J-2087D01*
G02X79800Y1562983I239J-321D01*
G01Y1533200D01*
X87000Y1526000D01*
X89247D01*
X89273Y1525974D01*
X127951D01*
X127977Y1526000D01*
X128500D01*
X141000Y1538500D01*
X184500D01*
X218600Y1504400D01*
Y1350300D01*
X210700Y1342400D01*
Y1063500D01*
X210000Y1062800D01*
X208300D01*
X197900Y1073200D01*
X195000D01*
X193300Y1071500D01*
Y1068900D01*
X206400Y1055800D01*
Y970614D01*
G03Y966640I950J-1987D01*
G01Y954900D01*
X114000Y862500D01*
Y840300D01*
X119000Y835300D01*
X157200D01*
X172500Y820000D01*
Y796600D01*
X204000Y765100D01*
Y595300D01*
X176500Y567800D01*
Y531500D01*
X193000Y515000D01*
Y372000D01*
X268500Y296500D01*
X274000D01*
Y295198D01*
X273822Y295177D01*
G03X259842Y279528I1769J-15650D01*
G01Y265748D01*
G03X291340I15749J0D01*
G01Y279528D01*
G03X275405Y295276I-15749J0D01*
G02X275000Y295676I-5J400D01*
G01Y296500D01*
X367464D01*
G02X367700Y295777I0J-400D01*
G03X370300I1300J-1777D01*
G02X370536Y296500I236J323D01*
G01X422500D01*
X426500Y292500D01*
X449000D01*
X549000Y192500D01*
X790435D01*
G03X794251I1908J1099D01*
G01X795000D01*
X797500Y195000D01*
Y198000D01*
X795000Y200500D01*
X787500D01*
X786000Y199000D01*
X552500D01*
X443000Y308500D01*
X268500D01*
X199000Y378000D01*
Y526000D01*
X198714Y526286D01*
Y526539D01*
X193814Y531440D01*
X193560D01*
X187500Y537500D01*
Y568500D01*
X193930Y574930D01*
X194066Y574844D01*
G03X197106Y577884I1184J1856D01*
G01X197020Y578020D01*
X211500Y592500D01*
Y737000D01*
X218000Y743500D01*
X230500D01*
X237500Y736500D01*
Y612500D01*
X245500Y604500D01*
Y581000D01*
X221500Y557000D01*
Y554358D01*
X221486Y554344D01*
Y447986D01*
X216000Y442500D01*
Y433500D01*
X229000Y420500D01*
Y382000D01*
X235000Y376000D01*
X245000D01*
X248500Y379500D01*
Y388000D01*
X246000Y390500D01*
Y553500D01*
X253000Y560500D01*
X272500D01*
X276000Y564000D01*
Y597000D01*
X275679Y597321D01*
X275669Y597383D01*
G03X272579Y599000I-2169J-383D01*
G01X259500D01*
X245000Y613500D01*
Y643500D01*
X248500Y647000D01*
X261000D01*
X282500Y625500D01*
Y613612D01*
G03X284854Y609970I1500J-1612D01*
G01X284978Y610022D01*
X286000Y609000D01*
X293500D01*
X308500Y594000D01*
X322500D01*
X332500Y584000D01*
Y569500D01*
X334000Y568000D01*
X348500D01*
X353000Y563500D01*
Y531800D01*
X313500Y492300D01*
Y430100D01*
G02X313115Y429700I-400J0D01*
G03Y425300I85J-2200D01*
G02X313500Y424900I-15J-400D01*
G01Y413612D01*
G03Y410388I1500J-1612D01*
G01Y405000D01*
X313000Y404500D01*
Y395650D01*
G02X312585Y395250I-400J0D01*
G03X313321Y391007I-85J-2200D01*
G01X313444Y391056D01*
X316000Y388500D01*
X326500D01*
X329500Y391500D01*
Y398500D01*
X333500Y402500D01*
Y408410D01*
G03Y408590I-2200J90D01*
G01Y493700D01*
X367500Y527700D01*
Y572000D01*
X337884Y601616D01*
Y606372D01*
X334783Y609474D01*
X322500D01*
Y617000D01*
X327500Y622000D01*
X485500D01*
X496000Y611500D01*
X540000D01*
X561000Y590500D01*
Y539000D01*
X559500Y537500D01*
X556000D01*
X551000Y532500D01*
Y522000D01*
X553500Y519500D01*
X559000D01*
X567000Y527500D01*
Y595000D01*
X525000Y637000D01*
X319500D01*
X308500Y648000D01*
Y796500D01*
X309000Y797000D01*
X315823D01*
X315937Y796886D01*
X338614D01*
X338700Y796800D01*
X341342D01*
X350181Y787960D01*
X440814D01*
X470314Y817461D01*
Y1763639D01*
X457439Y1776514D01*
X355239D01*
X279127Y1852627D01*
X201092D01*
G02X200809Y1853309I0J400D01*
G01X262500Y1915000D01*
X263671Y1913829D01*
X263553Y1913689D01*
G03X259842Y1903534I12038J-10155D01*
G01Y1889754D01*
G03X291340I15749J0D01*
G01Y1903534D01*
G03X265571Y1915685I-15749J0D01*
G01X265431Y1915569D01*
X264500Y1916500D01*
Y1917000D01*
X289948Y1942448D01*
X721552D01*
X724400Y1939600D01*
Y1927600D01*
X830000Y1822000D01*
Y1811500D01*
X810000Y1791500D01*
Y1786500D01*
X767500Y1744000D01*
Y1685000D01*
X750000Y1667500D01*
Y1661500D01*
X753500Y1658000D01*
X771000D01*
X775500Y1662500D01*
Y1740500D01*
X818000Y1783000D01*
Y1783882D01*
X818012Y1783914D01*
G03X818202Y1785000I-3012J1087D01*
G01Y1786702D01*
X839513Y1808013D01*
X845494D01*
X855298Y1798209D01*
Y1777674D01*
X893174Y1739798D01*
X902174D01*
X907298Y1734674D01*
X907299Y1734592D01*
G03X913702Y1734600I3201J8D01*
G01Y1737326D01*
X908710Y1742317D01*
G02X908993Y1743000I283J283D01*
G01X929374D01*
X934180Y1738194D01*
Y1693950D01*
X922000Y1681770D01*
Y1656500D01*
X935000Y1643500D01*
Y1638500D01*
X933000Y1636500D01*
X805500D01*
X801500Y1632500D01*
Y1618000D01*
X808000Y1611500D01*
X988500D01*
X991500Y1608500D01*
X1018000D01*
X1020000Y1606500D01*
Y1514500D01*
X1019200Y1513700D01*
X980700D01*
X980000Y1514400D01*
X930200D01*
X927600Y1511800D01*
Y1423400D01*
X934000Y1417000D01*
X1005500D01*
X1023500Y1399000D01*
X1029402D01*
Y1399276D01*
X1034398D01*
Y3937D01*
G02X1033465Y3004I-933J0D01*
G01X148780D01*
G37*
G36*
G01X76952Y1441117D02*
X60698Y1424864D01*
G03X59765Y1422761I2264J-2263D01*
G01X59761Y1422684D01*
X54500Y1417423D01*
Y1341500D01*
X67000Y1329000D01*
Y1321000D01*
X65500Y1319500D01*
X51636D01*
G03X48564I-1536J-2100D01*
G01X33500D01*
X30500Y1322500D01*
X25000D01*
X22500Y1325000D01*
Y1409500D01*
X29835Y1416835D01*
G02X30484Y1416714I283J-282D01*
G03X34118Y1419093I2016J886D01*
G01X34090Y1419124D01*
Y1419266D01*
X67931Y1453107D01*
X71631D01*
X77074Y1447664D01*
X77046Y1447555D01*
G03X76952Y1446781I3107J-770D01*
G01Y1441117D01*
G37*
G36*
G01X953000Y1654000D02*
X941086Y1665914D01*
Y1674809D01*
X949500Y1683223D01*
Y1743500D01*
X935200Y1757800D01*
X905700D01*
X896702Y1766798D01*
G02X896764Y1767415I282J283D01*
G03X897137Y1770773I-1217J1835D01*
G02Y1771327I289J277D01*
G03X893957I-1590J1523D01*
G02Y1770773I-289J-277D01*
G03X893712Y1770467I1590J-1524D01*
G02X893095Y1770405I-334J220D01*
G01X884913Y1778587D01*
G02X884978Y1779206I282J283D01*
G03X881933Y1782251I-1197J1848D01*
G02X881314Y1782186I-336J217D01*
G01X875000Y1788500D01*
Y1810500D01*
X727500Y1958000D01*
X155402D01*
Y1972798D01*
X153498Y1974702D01*
X132402D01*
X130198Y1972498D01*
Y1954102D01*
X131150Y1953150D01*
X77332Y1899332D01*
X72748D01*
G03X68552I-2098J-1540D01*
G01X53134D01*
X45328Y1891526D01*
Y1889339D01*
G03X46072Y1885712I1540J-1574D01*
G01X46200Y1885662D01*
Y1880954D01*
X44286Y1879040D01*
Y1871498D01*
X45948Y1869836D01*
Y1820058D01*
X44405Y1818516D01*
X38491D01*
X37300Y1819707D01*
Y1881586D01*
X33895Y1884991D01*
X8000D01*
Y1881778D01*
X5883Y1879661D01*
X3004D01*
Y1988189D01*
G02X3937Y1989122I933J0D01*
G01X1033465D01*
G02X1034398Y1988189I0J-933D01*
G01Y1710976D01*
X1032500D01*
Y1689000D01*
X1028000Y1684500D01*
X1024720D01*
X1020000Y1679780D01*
Y1674500D01*
X996000D01*
X995000Y1673500D01*
X978500D01*
X973500Y1668500D01*
Y1662000D01*
X965500Y1654000D01*
X953000D01*
G37*
G36*
G01X4038Y1816096D02*
X4000Y1816133D01*
Y1817500D01*
X4500Y1818000D01*
X26000D01*
X29500Y1814500D01*
X40000D01*
X41900Y1812600D01*
Y1804500D01*
X40400Y1803000D01*
X25500D01*
X23000Y1800500D01*
X4500D01*
X4000Y1801000D01*
Y1802320D01*
X4025Y1802344D01*
X14797D01*
X15002Y1802549D01*
Y1803305D01*
X14809Y1803498D01*
X4038D01*
X4000Y1803535D01*
Y1805469D01*
X4025Y1805494D01*
X14797D01*
X15002Y1805698D01*
Y1806454D01*
X14809Y1806646D01*
X4038D01*
X4000Y1806684D01*
Y1808619D01*
X4025Y1808644D01*
X14797D01*
X15002Y1808848D01*
Y1809604D01*
X14809Y1809796D01*
X4038D01*
X4000Y1809834D01*
Y1811768D01*
X4025Y1811792D01*
X14797D01*
X15002Y1811997D01*
Y1812753D01*
X14809Y1812946D01*
X4038D01*
X4000Y1812983D01*
Y1814918D01*
X4025Y1814942D01*
X14797D01*
X15002Y1815147D01*
Y1815903D01*
X14809Y1816096D01*
X4038D01*
G37*
G36*
G01Y1834994D02*
X4000Y1835031D01*
Y1872000D01*
X12938Y1880938D01*
X32027D01*
X32100Y1880865D01*
Y1822755D01*
X31645Y1822300D01*
X20217D01*
X17217Y1819300D01*
X4200D01*
X4000Y1819500D01*
Y1821217D01*
X4025Y1821242D01*
X14797D01*
X15002Y1821446D01*
Y1822202D01*
X14809Y1822394D01*
X4038D01*
X4000Y1822432D01*
Y1824367D01*
X4025Y1824392D01*
X14797D01*
X15002Y1824596D01*
Y1825352D01*
X14809Y1825544D01*
X4038D01*
X4000Y1825582D01*
Y1827517D01*
X4025Y1827542D01*
X14797D01*
X15002Y1827746D01*
Y1828502D01*
X14809Y1828694D01*
X4038D01*
X4000Y1828732D01*
Y1830666D01*
X4025Y1830690D01*
X14797D01*
X15002Y1830895D01*
Y1831651D01*
X14809Y1831844D01*
X4038D01*
X4000Y1831881D01*
Y1833816D01*
X4025Y1833840D01*
X14797D01*
X15002Y1834045D01*
Y1834801D01*
X14809Y1834994D01*
X4038D01*
G37*
G36*
G01X79000Y19000D02*
X68000Y30000D01*
Y43200D01*
X72548Y47748D01*
X83152D01*
X83300Y47600D01*
Y40700D01*
X87000Y37000D01*
X94700D01*
X102300Y44600D01*
X112600D01*
X113100Y44100D01*
Y42200D01*
X114100Y41200D01*
X117900D01*
X121700Y45000D01*
X127300D01*
X128100Y45800D01*
Y47900D01*
X128600Y48400D01*
X136300D01*
X142000Y42700D01*
Y35500D01*
X141526Y35026D01*
X141401Y35081D01*
G03X124252Y34029I-7542J-17350D01*
G01X124205Y34002D01*
X123502D01*
X121856Y32355D01*
X121848Y32348D01*
G03X119241Y29741I12010J-14617D01*
G01X119234Y29733D01*
X117102Y27602D01*
X101102D01*
X101101Y27600D01*
X100500D01*
X99500Y26600D01*
Y21300D01*
X97200Y19000D01*
X79000D01*
G37*
G36*
G01X45000Y801458D02*
G03Y805542I-1613J2042D01*
G01Y813000D01*
X48000Y816000D01*
X51500D01*
X76800Y790700D01*
Y775600D01*
X78700Y773700D01*
X82000D01*
X83700Y775400D01*
Y778300D01*
X84800Y779400D01*
X145100D01*
X151000Y773500D01*
Y733500D01*
X150500Y733000D01*
X147500D01*
X146000Y734500D01*
X98000D01*
X45000Y787500D01*
Y801458D01*
G37*
G36*
G01X104698Y1028302D02*
X116000Y1017000D01*
Y981500D01*
X127500Y970000D01*
Y950000D01*
X121500Y944000D01*
X74000D01*
X62800Y955200D01*
Y1006400D01*
X83500Y1027100D01*
Y1038347D01*
G03Y1040853I-1811J1253D01*
G01Y1048147D01*
G03Y1050653I-1811J1253D01*
G01Y1052500D01*
X88500Y1057500D01*
X100000D01*
X103913Y1053587D01*
Y1030257D01*
X103912Y1030246D01*
G03Y1029754I2188J-246D01*
G01X103913Y1029743D01*
Y1029087D01*
X104402Y1028598D01*
X104408Y1028591D01*
G03X104698Y1028302I1693J1408D01*
G37*
G36*
G01X140298Y1633374D02*
X147936Y1625736D01*
G03X152464Y1630264I2264J2264D01*
G01X146702Y1636026D01*
Y1640333D01*
G02X147384Y1640616I400J0D01*
G01X297500Y1490500D01*
Y1475000D01*
X286000Y1463500D01*
X266000D01*
X249314Y1480186D01*
Y1506758D01*
X204858Y1551214D01*
X138761D01*
X138570Y1551023D01*
X138523D01*
X133954Y1546454D01*
X114954D01*
X110637Y1542137D01*
X110497Y1542260D01*
G03X107390Y1539153I-1447J-1660D01*
G01X107513Y1539013D01*
X107000Y1538500D01*
X92500D01*
X87500Y1543500D01*
Y1616851D01*
X104600Y1633951D01*
Y1665600D01*
X110000Y1671000D01*
X117000D01*
X129416Y1658584D01*
G02X129133Y1657901I-283J-283D01*
G01X126900D01*
G03Y1651498I0J-3202D01*
G01X129774D01*
X140298Y1640974D01*
Y1633374D01*
G37*
G36*
G01X352358Y793214D02*
X349019Y796553D01*
X349144Y796856D01*
X327500Y818500D01*
Y829000D01*
X334100Y835600D01*
Y1150600D01*
X339800Y1156300D01*
Y1212400D01*
X331500Y1220700D01*
Y1357000D01*
X325500Y1363000D01*
Y1366448D01*
G02X326146Y1366764I400J0D01*
G03Y1370236I1354J1736D01*
G02X325500Y1370552I-246J316D01*
G01Y1372464D01*
G02X326223Y1372700I400J0D01*
G03Y1375300I1777J1300D01*
G02X325500Y1375536I-323J236D01*
G01Y1379964D01*
G02X326223Y1380200I400J0D01*
G03Y1382800I1777J1300D01*
G02X325500Y1383036I-323J236D01*
G01Y1398500D01*
X330500Y1403500D01*
X340500D01*
X441500Y1302500D01*
Y1159897D01*
X426603Y1145000D01*
X413000D01*
X406500Y1138500D01*
Y1129500D01*
X411500Y1124500D01*
X422000D01*
X449500Y1152000D01*
Y1309000D01*
X363000Y1395500D01*
Y1447300D01*
X450200Y1534500D01*
Y1724700D01*
X464500Y1739000D01*
Y1748500D01*
X460000Y1753000D01*
X446500D01*
X442616Y1749116D01*
Y1735757D01*
X440216Y1733357D01*
X429896D01*
X429439Y1733814D01*
X401186D01*
X393456Y1741544D01*
X393084D01*
X392676Y1741952D01*
X368950D01*
X367858Y1743044D01*
Y1749636D01*
X369894Y1751672D01*
X379272D01*
X380500Y1752900D01*
Y1758500D01*
X372000Y1767000D01*
X364482D01*
X356174Y1758692D01*
Y1750921D01*
X353870Y1748617D01*
X345617D01*
G02X345317Y1749282I0J400D01*
G03X344593Y1752739I-1649J1459D01*
G02X344605Y1753471I168J363D01*
G03X342825Y1753502I-855J2029D01*
G02X342813Y1752770I-168J-363D01*
G03X341467Y1750795I855J-2029D01*
G01X341465Y1750715D01*
X339367Y1748617D01*
X314696D01*
X313000Y1750313D01*
Y1768500D01*
X292000Y1789500D01*
X200432D01*
G02X200043Y1789992I0J400D01*
G03X195757I-2143J508D01*
G02X195368Y1789500I-389J-92D01*
G01X192000D01*
X181500Y1779000D01*
Y1763500D01*
X191500Y1753500D01*
X199500D01*
X202000Y1751000D01*
Y1745500D01*
X164800Y1708300D01*
X138200D01*
X99000Y1669100D01*
Y1636605D01*
X80000Y1617605D01*
Y1587200D01*
X70500D01*
X68818Y1588882D01*
Y1595082D01*
X65000Y1598900D01*
Y1695000D01*
X69500Y1699500D01*
Y1711500D01*
X76000Y1718000D01*
X88500D01*
X91500Y1721000D01*
X100500D01*
X103000Y1718500D01*
X103238D01*
X103239Y1718498D01*
X113001D01*
X116002Y1721500D01*
X141894D01*
G02X142279Y1720992I0J-400D01*
G03X146086Y1721816I2121J-592D01*
G01X146040Y1721872D01*
Y1722198D01*
G02X146319Y1722382I200J1D01*
G03X149000Y1725668I881J2018D01*
G01Y1748600D01*
X161300Y1760900D01*
Y1780600D01*
X154700Y1787200D01*
Y1812500D01*
X153200Y1814000D01*
X150000D01*
X149000Y1813000D01*
Y1764000D01*
X141000Y1756000D01*
X120500D01*
X119000Y1754500D01*
X92500D01*
X91000Y1756000D01*
X67000D01*
X64500Y1758500D01*
Y1768100D01*
X72000Y1775600D01*
X81100D01*
X107900Y1802400D01*
Y1827700D01*
X99516Y1836084D01*
Y1847203D01*
G03X98275Y1850985I-1516J1597D01*
G01X98100Y1851007D01*
Y1853173D01*
X97273Y1854000D01*
X85344D01*
X84843Y1854502D01*
X74298D01*
X72700Y1856100D01*
Y1862400D01*
X78298Y1867998D01*
X124002D01*
X138900Y1853100D01*
X163200D01*
X169100Y1847200D01*
X194700D01*
X194872Y1847372D01*
X276950D01*
X353062Y1771260D01*
X455262D01*
X465060Y1761462D01*
Y819638D01*
X438637Y793214D01*
X352358D01*
G37*
G36*
G01X69500Y1740500D02*
X69000Y1741000D01*
Y1744500D01*
X69800Y1745300D01*
Y1747900D01*
X70400Y1748500D01*
X76500D01*
X78500Y1746500D01*
Y1743900D01*
X75100Y1740500D01*
X69500D01*
G37*
G36*
G01X193000Y1858500D02*
X192500Y1859000D01*
Y1860334D01*
X192501Y1860344D01*
G03X192512Y1860548I-2001J210D01*
G01Y1863749D01*
G03X192501Y1863954I-2012J-5D01*
G01X192500Y1863964D01*
Y1865500D01*
X182000Y1876000D01*
X171377D01*
X169868Y1877510D01*
X115074D01*
G03X111308Y1876181I-1574J-1540D01*
G01X111291Y1876000D01*
X109378D01*
X93690Y1891688D01*
Y1895690D01*
X129350Y1931350D01*
X131050D01*
X141700Y1942000D01*
X259500D01*
X262500Y1939000D01*
Y1926500D01*
X194500Y1858500D01*
X193000D01*
G37*
G36*
G01X116141Y15355D02*
Y17685D01*
G02X151575I17717J46D01*
G01Y15355D01*
X141733D01*
Y17700D01*
G03X125983I-7875J32D01*
G01Y15355D01*
X116141D01*
G37*
G36*
G01X224114Y1507458D02*
X192500Y1539072D01*
Y1541500D01*
X194500Y1543500D01*
X204000D01*
X243500Y1504000D01*
Y1475500D01*
X273500Y1445500D01*
X308000D01*
X314000Y1439500D01*
Y1414000D01*
X303500Y1403500D01*
X302322D01*
X302284Y1403517D01*
G03X300479Y1403500I-884J-2017D01*
G01X295000D01*
X282600Y1391100D01*
Y1380400D01*
X285500Y1377500D01*
Y1209500D01*
X296000Y1199000D01*
X306000D01*
X310383Y1194617D01*
X310357Y1194508D01*
G03X313008Y1191857I2143J-508D01*
G01X313117Y1191883D01*
X315500Y1189500D01*
X318500D01*
X326806Y1181194D01*
G02X326673Y1180541I-283J-282D01*
G03X328854Y1176764I827J-2041D01*
G02X329500Y1176448I246J-316D01*
G01Y1162400D01*
X325300Y1158200D01*
Y845400D01*
X320098Y840198D01*
X320091Y840192D01*
G03X319808Y839909I1409J-1692D01*
G01X319802Y839902D01*
X300000Y820100D01*
Y660000D01*
X290000Y650000D01*
X270500D01*
X249900Y670600D01*
Y767400D01*
X166300Y851000D01*
X138500D01*
X134000Y855500D01*
Y872300D01*
X216500Y954800D01*
Y1338000D01*
X224500Y1346000D01*
Y1507000D01*
X224114Y1507386D01*
Y1507458D01*
G37*
G36*
G01X218500Y1579000D02*
X135000Y1662500D01*
Y1689500D01*
X146500Y1701000D01*
X169500D01*
X211500Y1743000D01*
X224000D01*
X231500Y1735500D01*
Y1584500D01*
X226000Y1579000D01*
X218500D01*
G37*
G36*
G01X285500Y1748500D02*
X276500Y1757500D01*
X231427D01*
X226414Y1762513D01*
Y1766526D01*
G03X223336I-1539J1574D01*
G01Y1765237D01*
G02X222607Y1765008I-400J-1D01*
G03Y1762492I-1807J-1258D01*
G02X223336Y1762263I329J-228D01*
G01Y1761237D01*
X226390Y1758183D01*
G02X226107Y1757500I-283J-283D01*
G01X205129D01*
G02X204847Y1758184I0J400D01*
G03X201751I-1548J1566D01*
G02X201469Y1757500I-282J-284D01*
G01X191500D01*
X183000Y1766000D01*
Y1778500D01*
X191500Y1787000D01*
X289000D01*
X309500Y1766500D01*
Y1753000D01*
X305000Y1748500D01*
X285500D01*
G37*
G36*
G01X132939Y1954540D02*
X132200Y1953800D01*
X131400Y1954600D01*
Y1972000D01*
X132900Y1973500D01*
X153000D01*
X154200Y1972300D01*
Y1954540D01*
X132939D01*
G37*
G36*
G01X300389Y1702611D02*
X311582Y1691418D01*
X311595Y1691395D01*
G03X312418Y1690582I1905J1105D01*
G01X325383Y1677617D01*
X325357Y1677508D01*
G03X328008Y1674857I2143J-508D01*
G01X328117Y1674883D01*
X328300Y1674700D01*
Y1522700D01*
X317700Y1512100D01*
X299700D01*
X239000Y1572800D01*
Y1702500D01*
X243500Y1707000D01*
X256000D01*
X260389Y1702611D01*
X283206D01*
G02X283503Y1701944I-1J-400D01*
G03X282988Y1700600I1496J-1344D01*
G01Y1697400D01*
G03X286893Y1696721I2012J0D01*
G01X286941Y1696854D01*
X291362D01*
X291854Y1696362D01*
Y1695341D01*
X291721Y1695293D01*
G03X292399Y1691388I679J-1893D01*
G01X295600D01*
G03X296278Y1695294I0J2012D01*
G01X296146Y1695341D01*
Y1698140D01*
X293140Y1701146D01*
X286941D01*
X286894Y1701278D01*
G03X286497Y1701944I-1894J-678D01*
G02X286794Y1702611I298J267D01*
G01X300389D01*
G37*
G36*
G01X257874Y277166D02*
Y279496D01*
G02X293308I17717J46D01*
G01Y277166D01*
X283466D01*
Y279511D01*
G03X267716I-7875J32D01*
G01Y277166D01*
X257874D01*
G37*
G36*
G01X299000Y1206000D02*
X292000Y1213000D01*
Y1252464D01*
G02X292723Y1252700I400J0D01*
G03Y1255300I1777J1300D01*
G02X292000Y1255536I-323J236D01*
G01Y1377600D01*
X295500Y1381100D01*
Y1393000D01*
X296474Y1393974D01*
X302026D01*
X305000Y1391000D01*
Y1386500D01*
X308500Y1383000D01*
Y1365500D01*
X324000Y1350000D01*
Y1250000D01*
X314500Y1240500D01*
Y1231241D01*
G02X313962Y1230866I-400J0D01*
G03Y1226734I-762J-2066D01*
G02X314500Y1226359I138J-375D01*
G01Y1215780D01*
G02X314311Y1215580I-200J0D01*
G03Y1211184I126J-2198D01*
G02X314500Y1210984I-11J-200D01*
G01Y1209000D01*
X311500Y1206000D01*
X299000D01*
G37*
G36*
G01X328000Y1445500D02*
X325500Y1448000D01*
Y1499300D01*
X339000Y1512800D01*
Y1702500D01*
X336726Y1704773D01*
Y1705680D01*
X333693Y1708714D01*
X333684Y1708781D01*
G03X330992Y1710643I-2184J-281D01*
G01X330883Y1710617D01*
X330400Y1711100D01*
X317553D01*
G02X317161Y1711577I0J400D01*
G03X312839I-2161J423D01*
G02X312447Y1711100I-392J-77D01*
G01X308100D01*
X307350Y1711850D01*
X306150D01*
X302000Y1716000D01*
Y1719901D01*
X302167Y1719929D01*
G03X302505Y1724186I-367J2171D01*
G02X302350Y1724848I128J379D01*
G01X307399Y1729896D01*
X311805D01*
G02X312020Y1729159I0J-400D01*
G03X314808Y1725796I1180J-1859D01*
G02X315392I292J-274D01*
G03X318180Y1729159I1608J1504D01*
G02X318395Y1729896I215J337D01*
G01X356299D01*
X363101Y1736698D01*
X376415D01*
G02X376813Y1736253I1J-400D01*
G03X380797Y1734728I2187J-253D01*
G02X381412Y1734774I327J-231D01*
G03X385202Y1736299I1588J1526D01*
G02X385602Y1736698I400J-1D01*
G01X390499D01*
X398637Y1728560D01*
X398640D01*
X398800Y1728400D01*
X425100D01*
X431000Y1722500D01*
Y1679000D01*
X427500Y1675500D01*
Y1663000D01*
X442000Y1648500D01*
Y1542500D01*
X345000Y1445500D01*
X328000D01*
G37*
G36*
G01X257874Y1901172D02*
Y1903502D01*
G02X293308I17717J46D01*
G01Y1901172D01*
X283466D01*
Y1903517D01*
G03X267716I-7875J32D01*
G01Y1901172D01*
X257874D01*
G37*
G36*
G01X806500Y1618500D02*
X805500Y1619500D01*
Y1632500D01*
X806500Y1633500D01*
X997042D01*
Y1633300D01*
X1019200D01*
X1020000Y1632500D01*
Y1625000D01*
X1019000Y1624000D01*
X994064D01*
X993583Y1624481D01*
G03X988803Y1622393I-1981J-1981D01*
G01X988806Y1622306D01*
X985000Y1618500D01*
X806500D01*
G37*
G36*
G01X998900Y1423100D02*
X998300Y1422500D01*
X934500D01*
X932000Y1425000D01*
Y1509500D01*
X932700Y1510200D01*
X981000D01*
X981800Y1511000D01*
X1019500D01*
X1020000Y1510500D01*
Y1434000D01*
X1009100Y1423100D01*
X998900D01*
G37*
%LPC*%
G75*
G36*
G01X17716Y281496D02*
G02X49214I15749J0D01*
G01Y267716D01*
G02X17716I-15749J1D01*
G01Y281496D01*
G37*
G36*
G01X42819Y1055581D02*
G03X42256Y1055691I-335J-218D01*
G02X42662Y1058944I-1256J1809D01*
G03X43236Y1058912I303J262D01*
G02X42819Y1055581I1764J-1912D01*
G37*
G36*
G01X27969Y991852D02*
G03X27630Y992405I-369J154D01*
G02X30109Y993753I195J2595D01*
G03X30389Y993167I351J-192D01*
G02X27969Y991852I-390J-2167D01*
G37*
G36*
G01X876500Y1055702D02*
X898163D01*
X899884Y1057423D01*
G02X902998Y1054309I1557J-1557D01*
G01X899987Y1051298D01*
X876500D01*
G02Y1055702I0J2202D01*
G37*
G36*
G01X900807Y1732591D02*
G03X900193I-307J-255D01*
G02Y1735409I-1693J1409D01*
G03X900807I307J255D01*
G02Y1732591I1693J-1409D01*
G37*
G36*
G01X915525Y1718379D02*
X915538Y1718325D01*
X920807Y1713057D01*
G02X917693Y1709943I-1557J-1557D01*
G01X912425Y1715212D01*
X912371Y1715225D01*
G02X910475Y1717121I629J2525D01*
G01X910462Y1717175D01*
X908298Y1719338D01*
Y1724700D01*
G02X912702I2202J0D01*
G01Y1721162D01*
X913575Y1720288D01*
X913629Y1720275D01*
G02X915525Y1718379I-629J-2525D01*
G37*
G36*
G01X905275Y1658868D02*
X866225D01*
X857798Y1667295D01*
Y1694602D01*
G02X861202I1702J1398D01*
G01Y1668705D01*
X867635Y1662272D01*
X903865D01*
X913548Y1671955D01*
Y1686102D01*
G02X916952I1702J1398D01*
G01Y1670545D01*
X905275Y1658868D01*
G37*
G36*
G01X879872Y1649119D02*
G03X879334I-269J-296D01*
G02X876223Y1652230I-1481J1630D01*
G03Y1652768I-296J269D01*
G02X879334Y1655879I1630J1481D01*
G03X879872I269J296D01*
G02X882983Y1652768I1481J-1630D01*
G03Y1652230I296J-269D01*
G02X879872Y1649119I-1630J-1481D01*
G37*
G36*
G01X835019Y1577370D02*
G03X834481I-269J-296D01*
G02X831370Y1580481I-1481J1630D01*
G03Y1581019I-296J269D01*
G02X834481Y1584130I1630J1481D01*
G03X835019I269J296D01*
G02X837981I1481J-1630D01*
G03X838519I269J296D01*
G02X841481I1481J-1630D01*
G03X842019I269J296D01*
G02X845130Y1581019I1481J-1630D01*
G03Y1580481I296J-269D01*
G02X842019Y1577370I-1630J-1481D01*
G03X841481I-269J-296D01*
G02X838519I-1481J1630D01*
G03X837981I-269J-296D01*
G02X835019I-1481J1630D01*
G37*
G36*
G01X875352Y1532880D02*
Y1528381D01*
X875346Y1528293D01*
G02X870530Y1528470I-2405J177D01*
G01Y1532870D01*
G02X875352Y1532880I2411J0D01*
G37*
G36*
G01X147006D02*
Y1528381D01*
X147000Y1528293D01*
G02X142184Y1528470I-2405J177D01*
G01Y1532870D01*
G02X147006Y1532880I2411J0D01*
G37*
G36*
G01X869452Y1522831D02*
Y1519534D01*
X869445Y1519447D01*
G02X865430Y1519621I-2004J174D01*
G01Y1522821D01*
G02X869452Y1522831I2011J0D01*
G37*
G36*
G01X141106D02*
Y1519534D01*
X141099Y1519447D01*
G02X137084Y1519621I-2004J174D01*
G01Y1522821D01*
G02X141106Y1522831I2011J0D01*
G37*
G36*
G01X875352Y1513982D02*
Y1509483D01*
X875346Y1509395D01*
G02X870530Y1509572I-2405J177D01*
G01Y1513972D01*
G02X875352Y1513982I2411J0D01*
G37*
G36*
G01X147006D02*
Y1509483D01*
X147000Y1509395D01*
G02X142184Y1509572I-2405J177D01*
G01Y1513972D01*
G02X147006Y1513982I2411J0D01*
G37*
G36*
G01X869452Y1503933D02*
Y1500636D01*
X869445Y1500549D01*
G02X865430Y1500723I-2004J174D01*
G01Y1503923D01*
G02X869452Y1503933I2011J0D01*
G37*
G36*
G01X141106D02*
Y1500636D01*
X141099Y1500549D01*
G02X137084Y1500723I-2004J174D01*
G01Y1503923D01*
G02X141106Y1503933I2011J0D01*
G37*
G36*
G01X875352Y1495084D02*
Y1490585D01*
X875346Y1490497D01*
G02X870530Y1490674I-2405J177D01*
G01Y1495074D01*
G02X875352Y1495084I2411J0D01*
G37*
G36*
G01X147006D02*
Y1490585D01*
X147000Y1490497D01*
G02X142184Y1490674I-2405J177D01*
G01Y1495074D01*
G02X147006Y1495084I2411J0D01*
G37*
G36*
G01X869452Y1485036D02*
Y1481739D01*
X869445Y1481652D01*
G02X865430Y1481826I-2004J174D01*
G01Y1485026D01*
G02X869452Y1485036I2011J0D01*
G37*
G36*
G01X141106D02*
Y1481739D01*
X141099Y1481652D01*
G02X137084Y1481826I-2004J174D01*
G01Y1485026D01*
G02X141106Y1485036I2011J0D01*
G37*
G36*
G01X916905Y1454490D02*
X908986D01*
X908891Y1454396D01*
Y1453871D01*
X909024Y1453824D01*
G02X908346Y1449918I-678J-1894D01*
G01X905146D01*
G02X904467Y1453823I0J2012D01*
G01X904600Y1453871D01*
Y1456174D01*
X907208Y1458782D01*
X916905D01*
X916952Y1458915D01*
G02X920858Y1458237I1894J-678D01*
G01Y1455037D01*
G02X916953Y1454358I-2012J0D01*
G01X916905Y1454490D01*
G37*
G36*
G01X176121Y1453823D02*
X176254Y1453871D01*
Y1456174D01*
X178862Y1458782D01*
X188559D01*
X188606Y1458915D01*
G02X192512Y1458237I1894J-678D01*
G01Y1455036D01*
G02X188607Y1454358I-2012J1D01*
G01X188559Y1454490D01*
X180640D01*
X180546Y1454396D01*
Y1453871D01*
X180678Y1453824D01*
G02X180000Y1449918I-678J-1894D01*
G01X176799D01*
G02X176121Y1453823I1J2012D01*
G37*
G36*
G01X875352Y1444691D02*
Y1440192D01*
X875346Y1440104D01*
G02X870530Y1440281I-2405J177D01*
G01Y1444681D01*
G02X875352Y1444691I2411J0D01*
G37*
G36*
G01X147006D02*
Y1440192D01*
X147000Y1440104D01*
G02X142184Y1440281I-2405J177D01*
G01Y1444681D01*
G02X147006Y1444691I2411J0D01*
G37*
G36*
G01X869452Y1434642D02*
Y1431345D01*
X869445Y1431258D01*
G02X865430Y1431432I-2004J174D01*
G01Y1434632D01*
G02X869452Y1434642I2011J0D01*
G37*
G36*
G01X141106D02*
Y1431345D01*
X141099Y1431258D01*
G02X137084Y1431432I-2004J174D01*
G01Y1434632D01*
G02X141106Y1434642I2011J0D01*
G37*
G36*
G01X101508Y1421396D02*
G03X101500Y1421113I137J-145D01*
G02X98392Y1421204I-1600J-1513D01*
G03X98400Y1421487I-137J145D01*
G02X101508Y1421396I1600J1513D01*
G37*
G36*
G01X885044Y1374736D02*
G03X885692Y1374716I331J224D01*
G02X885613Y1372142I1746J-1342D01*
G03X884965Y1372162I-331J-224D01*
G02X885044Y1374736I-1746J1342D01*
G37*
G36*
G01X107012Y1371728D02*
Y1368431D01*
X107004Y1368344D01*
G02X102988Y1368518I-2004J174D01*
G01Y1371719D01*
G02X107012Y1371728I2012J-1D01*
G37*
G36*
G01X897237Y1365815D02*
G03Y1365261I289J-277D01*
G02X894057I-1590J-1523D01*
G03Y1365815I-289J277D01*
G02X897237I1590J1523D01*
G37*
G36*
G01X101912Y1362879D02*
Y1358380D01*
X101905Y1358292D01*
G02X97088Y1358469I-2405J177D01*
G01Y1362869D01*
G02X101912Y1362879I2412J0D01*
G37*
G36*
G01X107012Y1321334D02*
Y1318037D01*
X107004Y1317950D01*
G02X102988Y1318124I-2004J174D01*
G01Y1321325D01*
G02X107012Y1321334I2012J-1D01*
G37*
G36*
G01X101912Y1312486D02*
Y1307987D01*
X101905Y1307899D01*
G02X97088Y1308076I-2405J177D01*
G01Y1312477D01*
G02X101912Y1312486I2412J-1D01*
G37*
G36*
G01X107012Y1302437D02*
Y1299140D01*
X107004Y1299053D01*
G02X102988Y1299227I-2004J174D01*
G01Y1302428D01*
G02X107012Y1302437I2012J-1D01*
G37*
G36*
G01X29540Y1295871D02*
Y1292574D01*
X29533Y1292487D01*
G02X25518Y1292661I-2004J174D01*
G01Y1295862D01*
G02X29540Y1295871I2011J-1D01*
G37*
G36*
G01X101912Y1293588D02*
Y1289089D01*
X101905Y1289001D01*
G02X97088Y1289178I-2405J177D01*
G01Y1293579D01*
G02X101912Y1293588I2412J-1D01*
G37*
G36*
G01X107012Y1283539D02*
Y1280242D01*
X107004Y1280155D01*
G02X102988Y1280329I-2004J174D01*
G01Y1283530D01*
G02X107012Y1283539I2012J-1D01*
G37*
G36*
G01X29540Y1283273D02*
Y1279976D01*
X29533Y1279889D01*
G02X25518Y1280063I-2004J174D01*
G01Y1283264D01*
G02X29540Y1283273I2011J-1D01*
G37*
G36*
G01X101912Y1274690D02*
Y1270191D01*
X101905Y1270103D01*
G02X97088Y1270280I-2405J177D01*
G01Y1274681D01*
G02X101912Y1274690I2412J-1D01*
G37*
G36*
G01X29540Y1270674D02*
Y1267377D01*
X29533Y1267290D01*
G02X25518Y1267464I-2004J174D01*
G01Y1270665D01*
G02X29540Y1270674I2011J-1D01*
G37*
G36*
G01Y1258076D02*
Y1254779D01*
X29533Y1254692D01*
G02X25518Y1254866I-2004J174D01*
G01Y1258067D01*
G02X29540Y1258076I2011J-1D01*
G37*
G36*
G01X128481Y1225630D02*
G03X129019I269J296D01*
G02X131981I1481J-1630D01*
G03X132519I269J296D01*
G02X135481I1481J-1630D01*
G03X136019I269J296D01*
G02X139130Y1222519I1481J-1630D01*
G03Y1221981I296J-269D01*
G02X136019Y1218870I-1630J-1481D01*
G03X135481I-269J-296D01*
G02X132519I-1481J1630D01*
G03X131981I-269J-296D01*
G02X129019I-1481J1630D01*
G03X128481I-269J-296D01*
G02X125370Y1221981I-1481J1630D01*
G03Y1222519I-296J269D01*
G02X128481Y1225630I1630J1481D01*
G37*
G36*
G01X835019Y1175370D02*
G03X834481I-269J-296D01*
G02Y1178630I-1481J1630D01*
G03X835019I269J296D01*
G02X837981I1481J-1630D01*
G03X838519I269J296D01*
G02X841481I1481J-1630D01*
G03X842019I269J296D01*
G02Y1175370I1481J-1630D01*
G03X841481I-269J-296D01*
G02X838519I-1481J1630D01*
G03X837981I-269J-296D01*
G02X835019I-1481J1630D01*
G37*
G36*
G01X107981Y1178630D02*
G03X108519I269J296D01*
G02X111481I1481J-1630D01*
G03X112019I269J296D01*
G02X114981I1481J-1630D01*
G03X115519I269J296D01*
G02X118630Y1175519I1481J-1630D01*
G03Y1174981I296J-269D01*
G02X115519Y1171870I-1630J-1481D01*
G03X114981I-269J-296D01*
G02X112019I-1481J1630D01*
G03X111481I-269J-296D01*
G02X108519I-1481J1630D01*
G03X107981I-269J-296D01*
G02X104870Y1174981I-1481J1630D01*
G03Y1175519I-296J269D01*
G02X107981Y1178630I1630J1481D01*
G37*
G36*
G01X875352Y1127368D02*
Y1122869D01*
X875346Y1122781D01*
G02X870530Y1122958I-2405J177D01*
G01Y1127358D01*
G02X875352Y1127368I2411J0D01*
G37*
G36*
G01X147006D02*
Y1122869D01*
X147000Y1122781D01*
G02X142184Y1122958I-2405J177D01*
G01Y1127358D01*
G02X147006Y1127368I2411J0D01*
G37*
G36*
G01X869452Y1117319D02*
Y1114022D01*
X869445Y1113935D01*
G02X865430Y1114109I-2004J174D01*
G01Y1117309D01*
G02X869452Y1117319I2011J0D01*
G37*
G36*
G01X141106D02*
Y1114022D01*
X141099Y1113935D01*
G02X137084Y1114109I-2004J174D01*
G01Y1117309D01*
G02X141106Y1117319I2011J0D01*
G37*
G36*
G01X875352Y1108470D02*
Y1103971D01*
X875346Y1103883D01*
G02X870530Y1104060I-2405J177D01*
G01Y1108460D01*
G02X875352Y1108470I2411J0D01*
G37*
G36*
G01X147006D02*
Y1103971D01*
X147000Y1103883D01*
G02X142184Y1104060I-2405J177D01*
G01Y1108460D01*
G02X147006Y1108470I2411J0D01*
G37*
G36*
G01X869452Y1098421D02*
Y1095124D01*
X869445Y1095037D01*
G02X865430Y1095211I-2004J174D01*
G01Y1098411D01*
G02X869452Y1098421I2011J0D01*
G37*
G36*
G01X141106D02*
Y1095124D01*
X141099Y1095037D01*
G02X137084Y1095211I-2004J174D01*
G01Y1098411D01*
G02X141106Y1098421I2011J0D01*
G37*
G36*
G01X875352Y1089572D02*
Y1085073D01*
X875346Y1084985D01*
G02X870530Y1085162I-2405J177D01*
G01Y1089562D01*
G02X875352Y1089572I2411J0D01*
G37*
G36*
G01X147006D02*
Y1085073D01*
X147000Y1084985D01*
G02X142184Y1085162I-2405J177D01*
G01Y1089562D01*
G02X147006Y1089572I2411J0D01*
G37*
G36*
G01X869452Y1079524D02*
Y1076227D01*
X869445Y1076140D01*
G02X865430Y1076314I-2004J174D01*
G01Y1079514D01*
G02X869452Y1079524I2011J0D01*
G37*
G36*
G01X141106D02*
Y1076227D01*
X141099Y1076140D01*
G02X137084Y1076314I-2004J174D01*
G01Y1079514D01*
G02X141106Y1079524I2011J0D01*
G37*
G36*
G01X916905Y1048978D02*
X908986D01*
X908891Y1048884D01*
Y1048359D01*
X909024Y1048312D01*
G02X908346Y1044406I-678J-1894D01*
G01X905146D01*
G02X904467Y1048311I0J2012D01*
G01X904600Y1048359D01*
Y1050662D01*
X907208Y1053270D01*
X916905D01*
X916952Y1053403D01*
G02X920858Y1052725I1894J-678D01*
G01Y1049525D01*
G02X916953Y1048846I-2012J0D01*
G01X916905Y1048978D01*
G37*
G36*
G01X875352Y1039179D02*
Y1034680D01*
X875346Y1034592D01*
G02X870530Y1034769I-2405J177D01*
G01Y1039169D01*
G02X875352Y1039179I2411J0D01*
G37*
G36*
G01X147006D02*
Y1034680D01*
X147000Y1034592D01*
G02X142184Y1034769I-2405J177D01*
G01Y1039169D01*
G02X147006Y1039179I2411J0D01*
G37*
G36*
G01X869452Y1029130D02*
Y1025833D01*
X869445Y1025746D01*
G02X865430Y1025920I-2004J174D01*
G01Y1029120D01*
G02X869452Y1029130I2011J0D01*
G37*
G36*
G01X176519Y958370D02*
G03X175981I-269J-296D01*
G02Y961630I-1481J1630D01*
G03X176519I269J296D01*
G02Y958370I1481J-1630D01*
G37*
G36*
G01X897137Y960304D02*
G03Y959750I289J-277D01*
G02X893957I-1590J-1523D01*
G03Y960304I-289J277D01*
G02X897137I1590J1523D01*
G37*
G36*
G01X107012Y915822D02*
Y912525D01*
X107004Y912438D01*
G02X102988Y912612I-2004J174D01*
G01Y915813D01*
G02X107012Y915822I2012J-1D01*
G37*
G36*
G01X101912Y906974D02*
Y902475D01*
X101905Y902387D01*
G02X97088Y902564I-2405J177D01*
G01Y906965D01*
G02X101912Y906974I2412J-1D01*
G37*
G36*
G01X107012Y896925D02*
Y893628D01*
X107004Y893541D01*
G02X102988Y893715I-2004J174D01*
G01Y896916D01*
G02X107012Y896925I2012J-1D01*
G37*
G36*
G01X101912Y888076D02*
Y883577D01*
X101905Y883489D01*
G02X97088Y883666I-2405J177D01*
G01Y888067D01*
G02X101912Y888076I2412J-1D01*
G37*
G36*
G01X107012Y878027D02*
Y874730D01*
X107004Y874643D01*
G02X102988Y874817I-2004J174D01*
G01Y878018D01*
G02X107012Y878027I2012J-1D01*
G37*
G36*
G01X101912Y869178D02*
Y864679D01*
X101905Y864591D01*
G02X97088Y864768I-2405J177D01*
G01Y869168D01*
G02X101912Y869178I2412J0D01*
G37*
G36*
G01X128481Y820130D02*
G03X129019I269J296D01*
G02X131981I1481J-1630D01*
G03X132519I269J296D01*
G02X135481I1481J-1630D01*
G03X136019I269J296D01*
G02X139130Y817019I1481J-1630D01*
G03Y816481I296J-269D01*
G02X136019Y813370I-1630J-1481D01*
G03X135481I-269J-296D01*
G02X132519I-1481J1630D01*
G03X131981I-269J-296D01*
G02X129019I-1481J1630D01*
G03X128481I-269J-296D01*
G02X125370Y816481I-1481J1630D01*
G03Y817019I-296J269D01*
G02X128481Y820130I1630J1481D01*
G37*
G36*
G01X835019Y766370D02*
G03X834481I-269J-296D01*
G02X831370Y769481I-1481J1630D01*
G03Y770019I-296J269D01*
G02X834481Y773130I1630J1481D01*
G03X835019I269J296D01*
G02X837981I1481J-1630D01*
G03X838519I269J296D01*
G02X841481I1481J-1630D01*
G03X842019I269J296D01*
G02X845130Y770019I1481J-1630D01*
G03Y769481I296J-269D01*
G02X842019Y766370I-1630J-1481D01*
G03X841481I-269J-296D01*
G02X838519I-1481J1630D01*
G03X837981I-269J-296D01*
G02X835019I-1481J1630D01*
G37*
G36*
G01X875352Y721856D02*
Y717357D01*
X875346Y717269D01*
G02X870530Y717446I-2405J177D01*
G01Y721846D01*
G02X875352Y721856I2411J0D01*
G37*
G36*
G01X147006D02*
Y717357D01*
X147000Y717269D01*
G02X142184Y717446I-2405J177D01*
G01Y721846D01*
G02X147006Y721856I2411J0D01*
G37*
G36*
G01X869452Y711807D02*
Y708510D01*
X869445Y708423D01*
G02X865430Y708597I-2004J174D01*
G01Y711797D01*
G02X869452Y711807I2011J0D01*
G37*
G36*
G01X141106D02*
Y708510D01*
X141099Y708423D01*
G02X137084Y708597I-2004J174D01*
G01Y711797D01*
G02X141106Y711807I2011J0D01*
G37*
G36*
G01X875352Y702958D02*
Y698459D01*
X875346Y698371D01*
G02X870530Y698548I-2405J177D01*
G01Y702948D01*
G02X875352Y702958I2411J0D01*
G37*
G36*
G01X147006D02*
Y698459D01*
X147000Y698371D01*
G02X142184Y698548I-2405J177D01*
G01Y702948D01*
G02X147006Y702958I2411J0D01*
G37*
G36*
G01X869452Y692909D02*
Y689612D01*
X869445Y689525D01*
G02X865430Y689699I-2004J174D01*
G01Y692899D01*
G02X869452Y692909I2011J0D01*
G37*
G36*
G01X141106D02*
Y689612D01*
X141099Y689525D01*
G02X137084Y689699I-2004J174D01*
G01Y692899D01*
G02X141106Y692909I2011J0D01*
G37*
G36*
G01X875352Y684060D02*
Y679561D01*
X875346Y679473D01*
G02X870530Y679650I-2405J177D01*
G01Y684050D01*
G02X875352Y684060I2411J0D01*
G37*
G36*
G01X147006D02*
Y679561D01*
X147000Y679473D01*
G02X142184Y679650I-2405J177D01*
G01Y684050D01*
G02X147006Y684060I2411J0D01*
G37*
G36*
G01X869452Y674012D02*
Y670715D01*
X869445Y670628D01*
G02X865430Y670802I-2004J174D01*
G01Y674002D01*
G02X869452Y674012I2011J0D01*
G37*
G36*
G01X141106D02*
Y670715D01*
X141099Y670628D01*
G02X137084Y670802I-2004J174D01*
G01Y674002D01*
G02X141106Y674012I2011J0D01*
G37*
G36*
G01X50235Y651322D02*
G03X49842Y650707I-59J-396D01*
G02X46188Y650751I-1842J-1207D01*
G03X45957Y651366I-329J227D01*
G02X48218Y654877I543J2134D01*
G03X48842I312J251D01*
G02X50235Y651322I1718J-1377D01*
G37*
G36*
G01X916905Y643466D02*
X908986D01*
X908891Y643372D01*
Y642847D01*
X909024Y642800D01*
G02X908346Y638894I-678J-1894D01*
G01X905146D01*
G02X904467Y642799I0J2012D01*
G01X904600Y642847D01*
Y645150D01*
X907208Y647758D01*
X916905D01*
X916952Y647891D01*
G02X920858Y647213I1894J-678D01*
G01Y644013D01*
G02X916953Y643334I-2012J0D01*
G01X916905Y643466D01*
G37*
G36*
G01X176121Y642799D02*
X176254Y642847D01*
Y645150D01*
X178862Y647758D01*
X188559D01*
X188606Y647891D01*
G02X192512Y647213I1894J-678D01*
G01Y644012D01*
G02X188607Y643334I-2012J1D01*
G01X188559Y643466D01*
X180640D01*
X180546Y643372D01*
Y642847D01*
X180678Y642800D01*
G02X180000Y638894I-678J-1894D01*
G01X176799D01*
G02X176121Y642799I1J2012D01*
G37*
G36*
G01X78928Y637588D02*
G03X78951Y638237I-222J333D01*
G02X81525Y638147I1349J1740D01*
G03X81502Y637498I222J-333D01*
G02X78928Y637588I-1349J-1740D01*
G37*
G36*
G01X875352Y633667D02*
Y629168D01*
X875346Y629080D01*
G02X870530Y629257I-2405J177D01*
G01Y633657D01*
G02X875352Y633667I2411J0D01*
G37*
G36*
G01X869452Y623618D02*
Y620321D01*
X869445Y620234D01*
G02X865430Y620408I-2004J174D01*
G01Y623608D01*
G02X869452Y623618I2011J0D01*
G37*
G36*
G01X107012Y560704D02*
Y557407D01*
X107004Y557320D01*
G02X102988Y557494I-2004J174D01*
G01Y560695D01*
G02X107012Y560704I2012J-1D01*
G37*
G36*
G01X897137Y554792D02*
G03Y554238I289J-277D01*
G02X893957I-1590J-1523D01*
G03Y554792I-289J277D01*
G02X897137I1590J1523D01*
G37*
G36*
G01X101912Y551855D02*
Y547356D01*
X101905Y547268D01*
G02X97088Y547445I-2405J177D01*
G01Y551845D01*
G02X101912Y551855I2412J0D01*
G37*
G36*
G01X297688Y553666D02*
Y547935D01*
X292139Y542386D01*
X286933D01*
G03X286542Y541900I0J-400D01*
G02X282460Y543442I-2542J-556D01*
G01Y544025D01*
X283443Y545007D01*
X282460Y545989D01*
Y546746D01*
G02X286507Y548147I1540J2098D01*
G03X286892Y547640I385J-107D01*
G01X289962D01*
X292434Y550112D01*
Y553304D01*
X292271Y553334D01*
G02X290608Y556280I396J2166D01*
G03X290287Y556818I-374J141D01*
G02X292639Y558220I293J2182D01*
G03X292960Y557682I374J-141D01*
G02X294276Y557003I-293J-2182D01*
G03X294861I292J273D01*
G02X296091Y557669I1609J-1503D01*
G03X296396Y558207I-68J394D01*
G02X298829Y556831I2054J793D01*
G03X298524Y556293I68J-394D01*
G02X297688Y553666I-2054J-793D01*
G37*
G36*
G01X107012Y510310D02*
Y507013D01*
X107004Y506926D01*
G02X102988Y507100I-2004J174D01*
G01Y510301D01*
G02X107012Y510310I2012J-1D01*
G37*
G36*
G01X101912Y501462D02*
Y496963D01*
X101905Y496875D01*
G02X97088Y497052I-2405J177D01*
G01Y501453D01*
G02X101912Y501462I2412J-1D01*
G37*
G36*
G01X107012Y491413D02*
Y488116D01*
X107004Y488029D01*
G02X102988Y488203I-2004J174D01*
G01Y491404D01*
G02X107012Y491413I2012J-1D01*
G37*
G36*
G01X101912Y482564D02*
Y478065D01*
X101905Y477977D01*
G02X97088Y478154I-2405J177D01*
G01Y482555D01*
G02X101912Y482564I2412J-1D01*
G37*
G36*
G01X107012Y472515D02*
Y469218D01*
X107004Y469131D01*
G02X102988Y469305I-2004J174D01*
G01Y472506D01*
G02X107012Y472515I2012J-1D01*
G37*
G36*
G01X101912Y463666D02*
Y459167D01*
X101905Y459079D01*
G02X97088Y459256I-2405J177D01*
G01Y463656D01*
G02X101912Y463666I2412J0D01*
G37*
G36*
G01X128481Y414630D02*
G03X129019I269J296D01*
G02X131981I1481J-1630D01*
G03X132519I269J296D01*
G02X135481I1481J-1630D01*
G03X136019I269J296D01*
G02X139130Y411519I1481J-1630D01*
G03Y410981I296J-269D01*
G02X136019Y407870I-1630J-1481D01*
G03X135481I-269J-296D01*
G02X132519I-1481J1630D01*
G03X131981I-269J-296D01*
G02X129019I-1481J1630D01*
G03X128481I-269J-296D01*
G02X125370Y410981I-1481J1630D01*
G03Y411519I-296J269D01*
G02X128481Y414630I1630J1481D01*
G37*
G36*
G01X158983Y410708D02*
G03X159183Y410093I324J-235D01*
G02X156717Y409292I-683J-2093D01*
G03X156517Y409907I-324J235D01*
G02X158983Y410708I683J2093D01*
G37*
G36*
G01X52012Y372850D02*
X52092Y372852D01*
X61483Y382244D01*
X76577D01*
G02Y379164I2098J-1540D01*
G01X62759D01*
X54269Y370675D01*
X54267Y370595D01*
G02X52012Y372850I-2201J54D01*
G37*
G36*
G01X107981Y367630D02*
G03X108519I269J296D01*
G02X111481I1481J-1630D01*
G03X112019I269J296D01*
G02X114981I1481J-1630D01*
G03X115519I269J296D01*
G02X118630Y364519I1481J-1630D01*
G03Y363981I296J-269D01*
G02X115519Y360870I-1630J-1481D01*
G03X114981I-269J-296D01*
G02X112019I-1481J1630D01*
G03X111481I-269J-296D01*
G02X108519I-1481J1630D01*
G03X107981I-269J-296D01*
G02X104870Y363981I-1481J1630D01*
G03Y364519I-296J269D01*
G02X107981Y367630I1630J1481D01*
G37*
G36*
G01X875352Y316344D02*
Y311845D01*
X875346Y311757D01*
G02X870530Y311934I-2405J177D01*
G01Y316334D01*
G02X875352Y316344I2411J0D01*
G37*
G36*
G01X147006D02*
Y311845D01*
X147000Y311757D01*
G02X142184Y311934I-2405J177D01*
G01Y316334D01*
G02X147006Y316344I2411J0D01*
G37*
G36*
G01X869452Y306295D02*
Y302998D01*
X869445Y302911D01*
G02X865430Y303085I-2004J174D01*
G01Y306285D01*
G02X869452Y306295I2011J0D01*
G37*
G36*
G01X141106D02*
Y302998D01*
X141099Y302911D01*
G02X137084Y303085I-2004J174D01*
G01Y306285D01*
G02X141106Y306295I2011J0D01*
G37*
G36*
G01X875352Y297446D02*
Y292947D01*
X875346Y292859D01*
G02X870530Y293036I-2405J177D01*
G01Y297436D01*
G02X875352Y297446I2411J0D01*
G37*
G36*
G01X147006D02*
Y292947D01*
X147000Y292859D01*
G02X142184Y293036I-2405J177D01*
G01Y297436D01*
G02X147006Y297446I2411J0D01*
G37*
G36*
G01X869452Y287397D02*
Y284100D01*
X869445Y284013D01*
G02X865430Y284187I-2004J174D01*
G01Y287387D01*
G02X869452Y287397I2011J0D01*
G37*
G36*
G01X141106D02*
Y284100D01*
X141099Y284013D01*
G02X137084Y284187I-2004J174D01*
G01Y287387D01*
G02X141106Y287397I2011J0D01*
G37*
G36*
G01X875352Y278548D02*
Y274049D01*
X875346Y273961D01*
G02X870530Y274138I-2405J177D01*
G01Y278538D01*
G02X875352Y278548I2411J0D01*
G37*
G36*
G01X147006D02*
Y274049D01*
X147000Y273961D01*
G02X142184Y274138I-2405J177D01*
G01Y278538D01*
G02X147006Y278548I2411J0D01*
G37*
G36*
G01X869452Y268500D02*
Y265203D01*
X869445Y265116D01*
G02X865430Y265290I-2004J174D01*
G01Y268490D01*
G02X869452Y268500I2011J0D01*
G37*
G36*
G01X141106D02*
Y265203D01*
X141099Y265116D01*
G02X137084Y265290I-2004J174D01*
G01Y268490D01*
G02X141106Y268500I2011J0D01*
G37*
G36*
G01X176121Y237287D02*
X176254Y237335D01*
Y239638D01*
X178862Y242246D01*
X188559D01*
X188606Y242379D01*
G02X192512Y241701I1894J-678D01*
G01Y238500D01*
G02X188607Y237822I-2012J1D01*
G01X188559Y237954D01*
X180640D01*
X180546Y237860D01*
Y237335D01*
X180678Y237288D01*
G02X180000Y233382I-678J-1894D01*
G01X176799D01*
G02X176121Y237287I1J2012D01*
G37*
G36*
G01X875352Y228155D02*
Y223656D01*
X875346Y223568D01*
G02X870530Y223745I-2405J177D01*
G01Y228145D01*
G02X875352Y228155I2411J0D01*
G37*
G36*
G01X147006D02*
Y223656D01*
X147000Y223568D01*
G02X142184Y223745I-2405J177D01*
G01Y228145D01*
G02X147006Y228155I2411J0D01*
G37*
G36*
G01X869452Y218106D02*
Y214809D01*
X869445Y214722D01*
G02X865430Y214896I-2004J174D01*
G01Y218096D01*
G02X869452Y218106I2011J0D01*
G37*
G36*
G01X141106D02*
Y214809D01*
X141099Y214722D01*
G02X137084Y214896I-2004J174D01*
G01Y218096D01*
G02X141106Y218106I2011J0D01*
G37*
G36*
G01X107012Y155192D02*
Y151895D01*
X107004Y151808D01*
G02X102988Y151982I-2004J174D01*
G01Y155183D01*
G02X107012Y155192I2012J-1D01*
G37*
G36*
G01X168928Y149722D02*
G03Y149184I296J-269D01*
G02X165668I-1630J-1481D01*
G03Y149722I-296J269D01*
G02X168928I1630J1481D01*
G37*
G36*
G01X898091Y149233D02*
G03X898075Y148680I280J-285D01*
G02X894897Y148773I-1634J-1477D01*
G03X894913Y149326I-280J285D01*
G02X898091Y149233I1634J1477D01*
G37*
G36*
G01X101912Y146343D02*
Y141844D01*
X101905Y141756D01*
G02X97088Y141933I-2405J177D01*
G01Y146334D01*
G02X101912Y146343I2412J-1D01*
G37*
G36*
G01X107012Y104798D02*
Y101501D01*
X107004Y101414D01*
G02X102988Y101588I-2004J174D01*
G01Y104789D01*
G02X107012Y104798I2012J-1D01*
G37*
G36*
G01X101912Y95950D02*
Y91451D01*
X101905Y91363D01*
G02X97088Y91540I-2405J177D01*
G01Y95941D01*
G02X101912Y95950I2412J-1D01*
G37*
G36*
G01X107012Y85901D02*
Y82604D01*
X107004Y82517D01*
G02X102988Y82691I-2004J174D01*
G01Y85892D01*
G02X107012Y85901I2012J-1D01*
G37*
G36*
G01X101912Y77052D02*
Y72553D01*
X101905Y72465D01*
G02X97088Y72642I-2405J177D01*
G01Y77043D01*
G02X101912Y77052I2412J-1D01*
G37*
G36*
G01X107012Y67003D02*
Y63706D01*
X107004Y63619D01*
G02X102988Y63793I-2004J174D01*
G01Y66994D01*
G02X107012Y67003I2012J-1D01*
G37*
G36*
G01X101912Y58254D02*
Y53755D01*
X101905Y53667D01*
G02X97088Y53844I-2405J177D01*
G01Y58244D01*
G02X101912Y58254I2412J0D01*
G37*
G36*
G01X179319Y33870D02*
G03X178781I-269J-296D01*
G02X175670Y36981I-1481J1630D01*
G03Y37519I-296J269D01*
G02X178781Y40630I1630J1481D01*
G03X179319I269J296D01*
G02X182281I1481J-1630D01*
G03X182819I269J296D01*
G02X185781I1481J-1630D01*
G03X186319I269J296D01*
G02X189430Y37519I1481J-1630D01*
G03Y36981I296J-269D01*
G02X186319Y33870I-1630J-1481D01*
G03X185781I-269J-296D01*
G02X182819I-1481J1630D01*
G03X182281I-269J-296D01*
G02X179319I-1481J1630D01*
G37*
G36*
G01X652806Y1563104D02*
G02X650594I-1106J-1904D01*
G03Y1563796I-201J346D01*
G02X652806I1106J1904D01*
G03Y1563104I201J-346D01*
G37*
G36*
G01X647306D02*
G02X645094I-1106J-1904D01*
G03Y1563796I-201J346D01*
G02X647306I1106J1904D01*
G03Y1563104I201J-346D01*
G37*
G36*
G01X640806D02*
G02X638594I-1106J-1904D01*
G03Y1563796I-201J346D01*
G02X640806I1106J1904D01*
G03Y1563104I201J-346D01*
G37*
G36*
G01X635306D02*
G02X633094I-1106J-1904D01*
G03Y1563796I-201J346D01*
G02X635306I1106J1904D01*
G03Y1563104I201J-346D01*
G37*
G36*
G01X899975Y1456798D02*
X876500D01*
G02Y1461202I0J2202D01*
G01X898151D01*
X899884Y1462935D01*
G02X900499Y1463368I1556J-1557D01*
G03X900493Y1464094I-171J362D01*
G02X902342Y1464110I907J2006D01*
G03X902348Y1463384I171J-362D01*
G02X902998Y1459821I-907J-2006D01*
G01X899975Y1456798D01*
G37*
G36*
G01X194506Y1374904D02*
G02X192294I-1106J-1904D01*
G03Y1375596I-201J346D01*
G02Y1379404I1106J1904D01*
G03Y1380096I-201J346D01*
G02X194506I1106J1904D01*
G03Y1379404I201J-346D01*
G02Y1375596I-1106J-1904D01*
G03Y1374904I201J-346D01*
G37*
G36*
G01X927406Y1373904D02*
G02X925194I-1106J-1904D01*
G03Y1374596I-201J346D01*
G02X925185Y1378399I1106J1904D01*
G03Y1379089I-202J345D01*
G02X927415I1115J1899D01*
G03Y1378399I202J-345D01*
G02X927406Y1374596I-1115J-1899D01*
G03Y1373904I201J-346D01*
G37*
G36*
G01X927583Y968404D02*
G02X925371I-1106J-1904D01*
G03Y969096I-201J346D01*
G02X925354Y972894I1106J1904D01*
G03Y973583I-203J344D01*
G02X927600I1123J1894D01*
G03Y972894I203J-344D01*
G02X927583Y969096I-1123J-1894D01*
G03Y968404I201J-346D01*
G37*
G36*
G01X899999Y645798D02*
X876500D01*
G02Y650202I0J2202D01*
G01X898175D01*
X899884Y651911D01*
G02X900443Y652316I1555J-1558D01*
G03X900406Y653046I-181J357D01*
G02X902198Y653137I794J2054D01*
G03X902235Y652407I181J-357D01*
G02X902998Y648797I-794J-2053D01*
G01X899999Y645798D01*
G37*
G36*
G01X927471Y562904D02*
G02X925259I-1106J-1904D01*
G03Y563596I-201J346D01*
G02X925234Y567389I1106J1904D01*
G03Y568076I-205J343D01*
G02X927496I1131J1889D01*
G03Y567389I205J-344D01*
G02X927471Y563596I-1131J-1889D01*
G03Y562904I201J-346D01*
G37*
G36*
G01X72204Y532592D02*
G02X68896Y531397I-1204J-1844D01*
G03X68428Y531906I-382J118D01*
G02X65988Y533871I-429J1965D01*
G01Y537072D01*
G02X69893Y537751I2012J-1D01*
G01X69941Y537618D01*
X122059D01*
X122106Y537751D01*
G02X126012Y537073I1894J-678D01*
G01Y533872D01*
G02X122107Y533194I-2012J1D01*
G01X122059Y533326D01*
X72423D01*
G03X72204Y532592I0J-400D01*
G37*
G36*
G01X174071Y246816D02*
G02X171954Y246725I-976J-1974D01*
G03X171924Y247426I-207J342D01*
G02X170699Y249346I976J1974D01*
G01X170697Y249426D01*
X169562Y250560D01*
X145174D01*
G02Y253640I-1574J1540D01*
G01X170838D01*
X172874Y251603D01*
X172954Y251601D01*
G02X174041Y247517I-54J-2201D01*
G03X174071Y246816I207J-342D01*
G37*
G36*
G01X927453Y157404D02*
G02X925241I-1106J-1904D01*
G03Y158096I-201J346D01*
G02X925208Y161884I1106J1904D01*
G03Y162569I-207J343D01*
G02X927486I1139J1884D01*
G03Y161884I207J-343D01*
G02X927453Y158096I-1139J-1884D01*
G03Y157404I201J-346D01*
G37*
G36*
G01X29540Y1406107D02*
Y1402810D01*
X29533Y1402723D01*
G02X25518Y1402897I-2004J174D01*
G01Y1406098D01*
G02X29540Y1406107I2011J-1D01*
G37*
G36*
G01Y1393509D02*
Y1390212D01*
X29533Y1390125D01*
G02X25518Y1390299I-2004J174D01*
G01Y1393499D01*
G02X29540Y1393509I2011J0D01*
G37*
G36*
G01Y1380910D02*
Y1377613D01*
X29533Y1377526D01*
G02X25518Y1377700I-2004J174D01*
G01Y1380901D01*
G02X29540Y1380910I2011J-1D01*
G37*
G36*
G01Y1368312D02*
Y1365015D01*
X29533Y1364928D01*
G02X25518Y1365102I-2004J174D01*
G01Y1368303D01*
G02X29540Y1368312I2011J-1D01*
G37*
G36*
G01Y1355914D02*
Y1352617D01*
X29533Y1352530D01*
G02X25518Y1352704I-2004J174D01*
G01Y1355904D01*
G02X29540Y1355914I2011J0D01*
G37*
G36*
G01Y1343315D02*
Y1340018D01*
X29533Y1339931D01*
G02X25518Y1340105I-2004J174D01*
G01Y1343305D01*
G02X29540Y1343315I2011J0D01*
G37*
G36*
G01Y1330717D02*
Y1327420D01*
X29533Y1327333D01*
G02X25518Y1327507I-2004J174D01*
G01Y1330707D01*
G02X29540Y1330717I2011J0D01*
G37*
G36*
G01X883702Y1954202D02*
X882298Y1952798D01*
X859002D01*
X857798Y1954002D01*
Y1972998D01*
X859002Y1974202D01*
X881998D01*
X883702Y1972498D01*
Y1954202D01*
G37*
G36*
G01X37404Y1909055D02*
G02X5904I-15750J0D01*
G01Y1922835D01*
G02X37404I15750J0D01*
G01Y1909055D01*
G37*
G36*
G01X30441Y1968111D02*
G03X30126Y1967537I44J-398D01*
G02X27471Y1969860I-4126J-2037D01*
G03X27999Y1970248I128J379D01*
G02X30441Y1968111I2201J52D01*
G37*
G36*
G01X85467Y1955947D02*
G03X86021Y1955931I285J280D01*
G02X85933Y1952753I1479J-1631D01*
G03X85379Y1952769I-285J-280D01*
G02X82419Y1952770I-1479J1631D01*
G03X81881I-269J-296D01*
G02X78919I-1481J1630D01*
G03X78381I-269J-296D01*
G02X75419I-1481J1630D01*
G03X74881I-269J-296D01*
G02X71770Y1955881I-1481J1630D01*
G03Y1956419I-296J269D01*
G02X74881Y1959530I1630J1481D01*
G03X75419I269J296D01*
G02X78381I1481J-1630D01*
G03X78919I269J296D01*
G02X81908Y1956296I1481J-1630D01*
G03Y1956004I137J-146D01*
G02X82004Y1955908I-1508J-1604D01*
G03X82296I146J137D01*
G02X85467Y1955947I1604J-1508D01*
G37*
G36*
G01X799258Y1951677D02*
G03X798720I-269J-296D01*
G02X795609Y1954788I-1481J1630D01*
G03Y1955326I-296J269D01*
G02X798720Y1958437I1630J1481D01*
G03X799258I269J296D01*
G02X802220I1481J-1630D01*
G03X802758I269J296D01*
G02X805869Y1955326I1481J-1630D01*
G03Y1954788I296J-269D01*
G02X802758Y1951677I-1630J-1481D01*
G03X802220I-269J-296D01*
G02X799258I-1481J1630D01*
G37*
G36*
G01X797969Y1939026D02*
G03Y1938488I296J-269D01*
G02X794709I-1630J-1481D01*
G03Y1939026I-296J269D01*
G02X797969I1630J1481D01*
G37*
G36*
G01X875352Y1938392D02*
Y1933893D01*
X875346Y1933805D01*
G02X870530Y1933982I-2405J177D01*
G01Y1938382D01*
G02X875352Y1938392I2411J0D01*
G37*
G36*
G01X869452Y1928343D02*
Y1925046D01*
X869445Y1924959D01*
G02X865430Y1925133I-2004J174D01*
G01Y1928333D01*
G02X869452Y1928343I2011J0D01*
G37*
G36*
G01X875352Y1919494D02*
Y1914995D01*
X875346Y1914907D01*
G02X870530Y1915084I-2405J177D01*
G01Y1919484D01*
G02X875352Y1919494I2411J0D01*
G37*
G36*
G01X869452Y1909445D02*
Y1906148D01*
X869445Y1906061D01*
G02X865430Y1906235I-2004J174D01*
G01Y1909435D01*
G02X869452Y1909445I2011J0D01*
G37*
G36*
G01X875352Y1900596D02*
Y1896097D01*
X875346Y1896009D01*
G02X870530Y1896186I-2405J177D01*
G01Y1900586D01*
G02X875352Y1900596I2411J0D01*
G37*
G36*
G01X869452Y1890548D02*
Y1887251D01*
X869445Y1887164D01*
G02X865430Y1887338I-2004J174D01*
G01Y1890538D01*
G02X869452Y1890548I2011J0D01*
G37*
G36*
G01X916905Y1860002D02*
X908986D01*
X908891Y1859908D01*
Y1859383D01*
X909024Y1859336D01*
G02X908346Y1855430I-678J-1894D01*
G01X905146D01*
G02X904467Y1859335I0J2012D01*
G01X904600Y1859383D01*
Y1861686D01*
X907208Y1864294D01*
X916905D01*
X916952Y1864427D01*
G02X920858Y1863749I1894J-678D01*
G01Y1860549D01*
G02X916953Y1859870I-2012J0D01*
G01X916905Y1860002D01*
G37*
G36*
G01X875352Y1850203D02*
Y1845704D01*
X875346Y1845616D01*
G02X870530Y1845793I-2405J177D01*
G01Y1850193D01*
G02X875352Y1850203I2411J0D01*
G37*
G36*
G01X869452Y1840154D02*
Y1836857D01*
X869445Y1836770D01*
G02X865430Y1836944I-2004J174D01*
G01Y1840144D01*
G02X869452Y1840154I2011J0D01*
G37*
G36*
G01X899463Y1861798D02*
X876000D01*
G02Y1866202I0J2202D01*
G01X897639D01*
X899884Y1868447D01*
G02X900410Y1868835I1555J-1558D01*
G03X900373Y1869559I-187J353D01*
G02X902231Y1869654I827J2041D01*
G03X902268Y1868930I187J-353D01*
G02X902998Y1865333I-827J-2040D01*
G01X899463Y1861798D01*
G37*
G36*
G01X927506Y1779404D02*
G02X925294I-1106J-1904D01*
G03Y1780096I-201J346D01*
G02Y1783904I1106J1904D01*
G03Y1784596I-201J346D01*
G02X927506I1106J1904D01*
G03Y1783904I201J-346D01*
G02Y1780096I-1106J-1904D01*
G03Y1779404I201J-346D01*
G37*
G36*
G01X107981Y773130D02*
G03X108519I269J296D01*
G02X111481I1481J-1630D01*
G03X112019I269J296D01*
G02X114981I1481J-1630D01*
G03X115519I269J296D01*
G02X118630Y770019I1481J-1630D01*
G03Y769481I296J-269D01*
G02X115519Y766370I-1630J-1481D01*
G03X114981I-269J-296D01*
G02X112019I-1481J1630D01*
G03X111481I-269J-296D01*
G02X108519I-1481J1630D01*
G03X107981I-269J-296D01*
G02X104870Y769481I-1481J1630D01*
G03Y770019I-296J269D01*
G02X107981Y773130I1630J1481D01*
G37*
G36*
G01X107012Y966216D02*
Y962919D01*
X107004Y962832D01*
G02X102988Y963006I-2004J174D01*
G01Y966207D01*
G02X107012Y966216I2012J-1D01*
G37*
G36*
G01X101912Y957367D02*
Y952868D01*
X101905Y952780D01*
G02X97088Y952957I-2405J177D01*
G01Y957358D01*
G02X101912Y957367I2412J-1D01*
G37*
G36*
G01X128281Y1631730D02*
G03X128819I269J296D01*
G02X131781I1481J-1630D01*
G03X132319I269J296D01*
G02X135281I1481J-1630D01*
G03X135819I269J296D01*
G02X138930Y1628619I1481J-1630D01*
G03Y1628081I296J-269D01*
G02X135819Y1624970I-1630J-1481D01*
G03X135281I-269J-296D01*
G02X132319I-1481J1630D01*
G03X131781I-269J-296D01*
G02X128819I-1481J1630D01*
G03X128281I-269J-296D01*
G02X125170Y1628081I-1481J1630D01*
G03Y1628619I-296J269D01*
G02X128281Y1631730I1630J1481D01*
G37*
G36*
G01X104981Y1578330D02*
G03X105519I269J296D01*
G02X108481I1481J-1630D01*
G03X109019I269J296D01*
G02X111981I1481J-1630D01*
G03X112519I269J296D01*
G02X115630Y1575219I1481J-1630D01*
G03Y1574681I296J-269D01*
G02X112519Y1571570I-1630J-1481D01*
G03X111981I-269J-296D01*
G02X109019I-1481J1630D01*
G03X108481I-269J-296D01*
G02X105519I-1481J1630D01*
G03X104981I-269J-296D01*
G02X101870Y1574681I-1481J1630D01*
G03Y1575219I-296J269D01*
G02X104981Y1578330I1630J1481D01*
G37*
G36*
G01X147006Y1850203D02*
Y1845704D01*
X147000Y1845616D01*
G02X142184Y1845793I-2405J177D01*
G01Y1850194D01*
G02X147006Y1850203I2411J-1D01*
G37*
G36*
G01X141106Y1840154D02*
Y1836857D01*
X141099Y1836770D01*
G02X137084Y1836944I-2004J174D01*
G01Y1840145D01*
G02X141106Y1840154I2011J-1D01*
G37*
G36*
G01X107012Y1777240D02*
Y1773943D01*
X107004Y1773856D01*
G02X102988Y1774030I-2004J174D01*
G01Y1777230D01*
G02X107012Y1777240I2012J0D01*
G37*
G36*
G01X101912Y1768391D02*
Y1763892D01*
X101905Y1763804D01*
G02X97088Y1763981I-2405J177D01*
G01Y1768381D01*
G02X101912Y1768391I2412J0D01*
G37*
G36*
G01Y1717998D02*
Y1713499D01*
X101905Y1713411D01*
G02X97088Y1713588I-2405J177D01*
G01Y1717988D01*
G02X101912Y1717998I2412J0D01*
G37*
G36*
G01X107012Y1707949D02*
Y1704652D01*
X107004Y1704565D01*
G02X102988Y1704739I-2004J174D01*
G01Y1707939D01*
G02X107012Y1707949I2012J0D01*
G37*
G36*
G01X101912Y1699100D02*
Y1694601D01*
X101905Y1694513D01*
G02X97088Y1694690I-2405J177D01*
G01Y1699090D01*
G02X101912Y1699100I2412J0D01*
G37*
G36*
G01X107012Y1689051D02*
Y1685754D01*
X107004Y1685667D01*
G02X102988Y1685841I-2004J174D01*
G01Y1689041D01*
G02X107012Y1689051I2012J0D01*
G37*
G36*
G01X101912Y1680202D02*
Y1675703D01*
X101905Y1675615D01*
G02X97088Y1675792I-2405J177D01*
G01Y1680192D01*
G02X101912Y1680202I2412J0D01*
G37*
G36*
G01X398804Y1186049D02*
X398724Y1186047D01*
X390778Y1178100D01*
X385238D01*
G02X381042I-2098J1540D01*
G01X360749D01*
G02Y1181180I-1574J1540D01*
G01X381042D01*
G02X385238I2098J-1540D01*
G01X389502D01*
X396547Y1188224D01*
X396549Y1188304D01*
G02X398804Y1186049I2201J-54D01*
G37*
G36*
G01X422780Y1222301D02*
G02X422755Y1224124I-2017J884D01*
G03X423483Y1224134I362J170D01*
G02X423508Y1222311I2017J-884D01*
G03X422780Y1222301I-362J-170D01*
G37*
G36*
G01X392866Y1147579D02*
G02X390770Y1147644I-1108J-1903D01*
G03X390792Y1148347I-179J357D01*
G02X392888Y1148282I1108J1903D01*
G03X392866Y1147579I179J-357D01*
G37*
G36*
G01X360287Y805224D02*
G02X358413Y805768I-1487J-1624D01*
G03X358613Y806456I-71J394D01*
G02X361674Y809620I1487J1624D01*
G01X376942D01*
X387427Y820104D01*
X387415Y820200D01*
G02X390300Y823085I2585J300D01*
G01X390396Y823073D01*
X396460Y829138D01*
Y840638D01*
X399797Y843974D01*
X399799Y844054D01*
G02X404055Y843210I2201J-53D01*
G03X404363Y842672I373J-143D01*
G02X401802Y840636I-363J-2172D01*
G03X401120Y840943I-399J24D01*
G01X399540Y839362D01*
Y832564D01*
G03X400147Y832223I400J1D01*
G02X399886Y827959I1353J-2223D01*
G01X399747Y828069D01*
X392573Y820896D01*
X392585Y820800D01*
G02X389700Y817915I-2585J-300D01*
G01X389604Y817927D01*
X378218Y806540D01*
X361674D01*
G02X360487Y805912I-1574J1540D01*
G03X360287Y805224I71J-394D01*
G37*
G36*
G01X147006Y1938392D02*
Y1933893D01*
X147000Y1933805D01*
G02X142184Y1933982I-2405J177D01*
G01Y1938383D01*
G02X147006Y1938392I2411J-1D01*
G37*
G36*
G01X141106Y1928343D02*
Y1925046D01*
X141099Y1924959D01*
G02X137084Y1925133I-2004J174D01*
G01Y1928334D01*
G02X141106Y1928343I2011J-1D01*
G37*
G36*
G01X147006Y1919494D02*
Y1914995D01*
X147000Y1914907D01*
G02X142184Y1915084I-2405J177D01*
G01Y1919484D01*
G02X147006Y1919494I2411J0D01*
G37*
G36*
G01X141106Y1909445D02*
Y1906148D01*
X141099Y1906061D01*
G02X137084Y1906235I-2004J174D01*
G01Y1909436D01*
G02X141106Y1909445I2011J-1D01*
G37*
G36*
G01X147006Y1900596D02*
Y1896097D01*
X147000Y1896009D01*
G02X142184Y1896186I-2405J177D01*
G01Y1900587D01*
G02X147006Y1900596I2411J-1D01*
G37*
G36*
G01X141106Y1890548D02*
Y1887251D01*
X141099Y1887164D01*
G02X137084Y1887338I-2004J174D01*
G01Y1890539D01*
G02X141106Y1890548I2011J-1D01*
G37*
G36*
G01X291340Y1074793D02*
G02X259842I-15749J0D01*
G01Y1088573D01*
G02X291340I15749J0D01*
G01Y1074793D01*
G37*
G36*
G01Y671250D02*
G02X259842I-15749J0D01*
G01Y685030D01*
G02X291340I15749J0D01*
G01Y671250D01*
G37*
G36*
G01X280000Y1182000D02*
X277500Y1179500D01*
X266000D01*
X264500Y1181000D01*
Y1186500D01*
X269500Y1191500D01*
Y1363938D01*
X252356Y1381082D01*
Y1406147D01*
X252760Y1406552D01*
Y1406619D01*
X263137Y1416995D01*
Y1419491D01*
X261417Y1421211D01*
X259284D01*
X235623Y1397550D01*
Y1280321D01*
X247000Y1268944D01*
Y1254500D01*
X244500Y1252000D01*
X239000D01*
X230000Y1261000D01*
Y1400195D01*
X262805Y1433000D01*
X271888D01*
G02X275405Y1432605I1612J-1500D01*
G01X275418Y1432582D01*
X277500Y1430500D01*
Y1413000D01*
X275679Y1411179D01*
X275669Y1411117D01*
G02X271888Y1410000I-2169J383D01*
G01X267000D01*
X259500Y1402500D01*
Y1382668D01*
X276000Y1366168D01*
Y1190000D01*
X280000Y1186000D01*
Y1182000D01*
G37*
G36*
G01X315392Y856396D02*
G03X314808I-292J-274D01*
G02Y859404I-1608J1504D01*
G03X315392I292J274D01*
G02Y856396I1608J-1504D01*
G37*
G36*
G01X322909Y849307D02*
G03Y848693I255J-307D01*
G02X320091I-1409J-1693D01*
G03Y849307I-255J307D01*
G02X320200Y852777I1409J1692D01*
G03Y853423I-236J323D01*
G02X322800I1300J1777D01*
G03Y852777I236J-323D01*
G02X322909Y849307I-1300J-1778D01*
G37*
G36*
G01Y1719307D02*
G03Y1718693I255J-307D01*
G02X320091I-1409J-1693D01*
G03Y1719307I-255J307D01*
G02X320200Y1722777I1409J1692D01*
G03Y1723423I-236J323D01*
G02X322800I1300J1777D01*
G03Y1722777I236J-323D01*
G02X322909Y1719307I-1300J-1778D01*
G37*
G36*
G01X381161Y1675753D02*
G02X377326Y1675180I-1661J-2003D01*
G03X376976Y1675800I-334J220D01*
G02X378464Y1679540I-86J2200D01*
G01X382362D01*
X393297Y1690474D01*
X393299Y1690554D01*
G02X393960Y1692074I2201J-54D01*
G01Y1700902D01*
G02Y1705098I1540J2098D01*
G01Y1708862D01*
X379026Y1723797D01*
X378946Y1723799D01*
G02X376885Y1725386I54J2201D01*
G03X376378Y1725655I-384J-111D01*
G02X377815Y1728364I-678J2095D01*
G03X378322Y1728095I384J111D01*
G02X381201Y1726054I678J-2095D01*
G01X381203Y1725974D01*
X397040Y1710138D01*
Y1705098D01*
G02Y1700902I-1540J-2098D01*
G01Y1692074D01*
G02X395554Y1688299I-1540J-1574D01*
G01X395474Y1688297D01*
X383638Y1676460D01*
X381417D01*
G03X381161Y1675753I0J-400D01*
G37*
G54D30*
X899606Y1569567D03*
Y1396339D03*
Y1164055D03*
Y990827D03*
Y758543D03*
Y585315D03*
Y179803D03*
X171260Y1164055D03*
Y990827D03*
Y758543D03*
Y585315D03*
Y353031D03*
X72835Y1406811D03*
Y1233583D03*
Y828071D03*
Y595787D03*
Y422559D03*
Y190275D03*
X899606Y1975079D03*
Y1801851D03*
X171260Y1975079D03*
X72835Y1001299D03*
X171260Y1569567D03*
Y1801851D03*
X72835Y1639095D03*
G54D28*
X25000Y988000D03*
X47500Y660500D03*
X163170Y1210999D03*
X206700Y575000D03*
X401500Y395500D03*
X393500Y422000D03*
X808256Y783275D03*
X807756Y1188775D03*
Y1594275D03*
X393500Y852000D03*
X402000Y1196500D03*
X396637Y1176000D03*
X402000Y1695000D03*
G54D26*
X60306Y212338D03*
X70500Y242988D03*
X23291Y1062791D03*
X28000Y1444000D03*
X72500Y61161D03*
X96000Y119000D03*
X99300Y201000D03*
X100400Y208300D03*
X129000Y255500D03*
X114295Y338300D03*
X92700Y358400D03*
X125300Y438000D03*
X72500Y466673D03*
X96000Y524000D03*
X71000Y524464D03*
X89400Y603250D03*
X62426Y607740D03*
X95900Y605500D03*
X85223Y645227D03*
X70500Y648500D03*
X88600Y623300D03*
X96000Y930000D03*
X72500Y872185D03*
X117900Y1149200D03*
X88500Y1177300D03*
X129150Y1252050D03*
X96000Y1335000D03*
X96250Y1414400D03*
X99300Y1431200D03*
X110000Y1470000D03*
X118000D03*
X184461Y103368D03*
X159500Y181000D03*
X150557Y142854D03*
X154875Y160500D03*
X148000Y241500D03*
X171595Y308917D03*
X173800Y379800D03*
X170500Y478500D03*
X195250Y561300D03*
X200250Y572100D03*
X173095Y650354D03*
X159600Y581400D03*
X156800Y816000D03*
X161095Y980622D03*
X162200Y988000D03*
X148000Y1053500D03*
X171595Y1119941D03*
X158052Y1216052D03*
X147956Y1347802D03*
X140125Y1381300D03*
X173095Y1461378D03*
X148000Y1458000D03*
X171595Y1525453D03*
X220500Y67500D03*
X206500Y531250D03*
Y546250D03*
Y538750D03*
X214500Y1459000D03*
X344500Y71750D03*
X348256Y344114D03*
X349870Y348870D03*
X294500Y408000D03*
X293000Y385000D03*
X303200Y422600D03*
X331500Y389000D03*
X327500Y377000D03*
X343729Y455810D03*
X317500Y559000D03*
X297300Y505017D03*
X320100Y587200D03*
X363750Y54250D03*
X358000Y64000D03*
X360750Y124000D03*
X382000Y98000D03*
X405500Y277500D03*
X383750Y344500D03*
X391750D03*
X356257Y344176D03*
X405000Y289000D03*
X401500Y410250D03*
X410550Y420500D03*
X365100Y371200D03*
X364758Y429249D03*
X397000Y380250D03*
X375200Y371250D03*
Y429250D03*
X387249Y455882D03*
X379258Y455892D03*
X351729Y455810D03*
X350137Y451250D03*
X385607Y451232D03*
X385238Y774122D03*
X377250Y774500D03*
X385196Y779112D03*
X547659Y1560537D03*
X542159D03*
Y1566037D03*
X547659D03*
X663000Y535500D03*
X661500Y650500D03*
X662000Y826600D03*
X665000Y937000D03*
X660000Y1053500D03*
X662000Y1183500D03*
X657000Y1331500D03*
X662000Y1459000D03*
X782500Y648000D03*
X816500Y171000D03*
X824500D03*
X832500D03*
X844000Y190000D03*
X844050Y337300D03*
X857735Y553465D03*
X846200Y743300D03*
X857623Y958977D03*
X844600Y1148700D03*
X857688Y1364488D03*
X845600Y1554300D03*
X813000Y1585750D03*
X866961Y162539D03*
X876500Y251000D03*
X899941Y308917D03*
X883781Y564519D03*
X888719D03*
X865125Y544000D03*
X899941Y714429D03*
X883781Y970031D03*
X888719D03*
X865125Y949600D03*
X901300Y1060700D03*
X899941Y1119941D03*
X865125Y1346488D03*
X899941Y1525453D03*
X901500Y1681500D03*
X921900Y1722400D03*
X896500Y1681000D03*
X865125Y1751800D03*
X57800Y1961800D03*
X755995Y1968282D03*
X785239Y1960907D03*
X888719Y1781054D03*
X899941Y1930965D03*
X844700Y1945200D03*
X959000Y1657000D03*
Y1675000D03*
X117945Y743800D03*
X86900Y774750D03*
X93000Y1005700D03*
X96500Y1011200D03*
X72500Y1683209D03*
X177717Y1778162D03*
X180075Y1790692D03*
X331500Y819000D03*
X343770Y885897D03*
X343894Y880707D03*
X343760Y1257381D03*
X343822Y1252222D03*
X410550Y850500D03*
X360800Y858500D03*
X368700Y803750D03*
X375200Y858250D03*
X388250Y803300D03*
X420722Y820627D03*
X387292Y885897D03*
X379270D03*
X351792Y885835D03*
X379372Y880728D03*
X383757Y1145655D03*
X405500Y1192000D03*
X364300Y1174900D03*
X365200Y1229800D03*
X375200Y1229750D03*
X374200Y1174750D03*
X387292Y1257360D03*
X408300Y1237500D03*
X379270Y1257380D03*
X351750D03*
X400700Y1237500D03*
X379395Y1252274D03*
X351750Y1755500D03*
X425891Y812750D03*
X425890Y820729D03*
X425500Y1215250D03*
X112366Y1883985D03*
X171595Y1930965D03*
X190330Y913530D03*
X229500Y946600D03*
X273500Y1403500D03*
X293500Y738000D03*
X292000Y837000D03*
X303500Y853100D03*
X315000Y842000D03*
X295200Y913000D03*
X305200D03*
Y903000D03*
X295200D03*
X292500Y965500D03*
X294000Y1111500D03*
X191353Y1772940D03*
X197900Y1781500D03*
X207600Y1777500D03*
X268800Y1774600D03*
X302500Y1224000D03*
X295000Y1245000D03*
X348257Y1644132D03*
X356247Y1644123D03*
X356174Y1649291D03*
X369100Y1673700D03*
X365700Y1727700D03*
X383000Y1728700D03*
X385250Y1673000D03*
X420732Y1721757D03*
X425879Y1721724D03*
X425500Y1713750D03*
G54D33*
X1009500Y27500D03*
X1010500Y1966000D03*
G54D32*
X82087Y178464D03*
Y434370D03*
Y583976D03*
Y839882D03*
Y1245394D03*
Y1395000D03*
X162008Y191614D03*
Y341220D03*
Y597126D03*
Y1002638D03*
Y1152244D03*
Y1408150D03*
X890354Y191614D03*
Y341220D03*
Y597126D03*
Y746732D03*
Y1002638D03*
Y1152244D03*
Y1408150D03*
Y1557756D03*
X162008Y1963268D03*
X890354Y1813662D03*
Y1963268D03*
X82087Y28858D03*
Y989488D03*
X162008Y1557756D03*
X82087Y1650906D03*
X162008Y1813662D03*
G54D34*
X1010999Y43999D03*
X25499Y1950499D03*
X1010499D03*
G54D27*
X11811Y949378D03*
Y1067489D03*
Y1445441D03*
Y1484811D03*
Y1862763D03*
G54D36*
X1023228Y1694212D03*
G54D35*
X998032Y1896644D03*
G54D29*
X33469Y1029523D03*
X269690Y1490152D03*
G54D31*
X998032Y1075778D03*
Y680108D03*
Y156486D03*
%LPD*%
G75*
G36*
G01X15748Y279134D02*
Y281464D01*
G02X51182I17717J46D01*
G01Y279134D01*
X41340D01*
Y281479D01*
G03X25590I-7875J32D01*
G01Y279134D01*
X15748D01*
G37*
G36*
G01X3937Y1920473D02*
Y1922803D01*
G02X39371I17717J46D01*
G01Y1920473D01*
X29529D01*
Y1922818D01*
G03X13779I-7875J32D01*
G01Y1920473D01*
X3937D01*
G37*
G36*
G01X257874Y682668D02*
Y684998D01*
G02X293308I17717J46D01*
G01Y682668D01*
X283466D01*
Y685013D01*
G03X267716I-7875J32D01*
G01Y682668D01*
X257874D01*
G37*
G36*
G01Y1086211D02*
Y1088541D01*
G02X293308I17717J46D01*
G01Y1086211D01*
X283466D01*
Y1088556D01*
G03X267716I-7875J32D01*
G01Y1086211D01*
X257874D01*
G37*
G36*
G01X859500Y1954000D02*
X859000Y1954500D01*
Y1972500D01*
X859500Y1973000D01*
X881500D01*
X882500Y1972000D01*
Y1954700D01*
X881800Y1954000D01*
X859500D01*
G37*
G36*
G01X980314Y161014D02*
Y163344D01*
G02X1015748I17717J46D01*
G01Y161014D01*
X1005906D01*
Y163359D01*
G03X990156I-7875J32D01*
G01Y161014D01*
X980314D01*
G37*
G36*
G01Y684636D02*
Y686966D01*
G02X1015748I17717J46D01*
G01Y684636D01*
X1005906D01*
Y686981D01*
G03X990156I-7875J32D01*
G01Y684636D01*
X980314D01*
G37*
G36*
G01Y1080305D02*
Y1082635D01*
G02X1015748I17717J46D01*
G01Y1080305D01*
X1005906D01*
Y1082650D01*
G03X990156I-7875J32D01*
G01Y1080305D01*
X980314D01*
G37*
G36*
G01Y1901172D02*
Y1903502D01*
G02X1015748I17717J46D01*
G01Y1901172D01*
X1005906D01*
Y1903517D01*
G03X990156I-7875J32D01*
G01Y1901172D01*
X980314D01*
G37*
G54D10*
G01X328250Y441400D02*
Y493150D01*
X364000Y528900D01*
Y569630D01*
X336183Y597447D01*
Y605667D01*
X334078Y607772D01*
X302728D01*
X301000Y609500D01*
Y614000D01*
X295500Y619500D01*
Y640800D01*
X306000Y651300D01*
Y810900D01*
X318800Y823700D01*
G01X328250Y441400D02*
X331300Y438350D01*
Y408500D01*
G01X318800Y823700D02*
X331300Y836200D01*
Y838500D01*
G01X328250Y1233000D02*
Y1213050D01*
X331300Y1210000D01*
G01X335025Y1701725D02*
Y1682075D01*
X337100Y1680000D01*
Y1514500D01*
X322500Y1499900D01*
Y1359807D01*
X328250Y1354057D01*
Y1233000D01*
G01X331300Y1210000D02*
X335000Y1206300D01*
Y1158000D01*
X331300Y1154300D01*
Y838500D01*
G01X335025Y1701725D02*
Y1704975D01*
X331500Y1708500D01*
G01X859500Y1696000D02*
Y1668000D01*
X866930Y1660570D01*
X904570D01*
X915250Y1671250D01*
Y1687500D01*
X-63741Y15000D03*
X-42339Y1008909D03*
X-63741Y1977126D03*
X33465Y281496D03*
X11811Y571426D03*
Y949378D03*
Y1067489D03*
Y1484811D03*
Y1445441D03*
Y1862763D03*
X21654Y1922835D03*
X25499Y1950499D03*
X82087Y28858D03*
Y178464D03*
Y434370D03*
Y583976D03*
Y839882D03*
Y989488D03*
Y1245394D03*
Y1395000D03*
Y1650906D03*
Y1800512D03*
X133858Y17717D03*
X162008Y191614D03*
Y341220D03*
Y597126D03*
Y746732D03*
Y1002638D03*
Y1152244D03*
Y1408150D03*
Y1557756D03*
Y1813662D03*
Y1963268D03*
X275591Y279528D03*
Y685030D03*
Y1088573D03*
Y1903534D03*
X890354Y191614D03*
Y341220D03*
Y597126D03*
Y746732D03*
Y1002638D03*
Y1152244D03*
Y1408150D03*
Y1557756D03*
Y1813662D03*
Y1963268D03*
X1010999Y43999D03*
X998031Y163376D03*
Y686998D03*
Y1082667D03*
X1023228Y1416024D03*
Y1694212D03*
X998031Y1903534D03*
X1010499Y1950499D03*
X1101142Y15000D03*
Y1977126D03*
G54D20*
X990245Y1500976D03*
Y1496976D03*
Y1487976D03*
Y1460976D03*
Y1456976D03*
Y1447976D03*
Y1566976D03*
Y1540976D03*
Y1536976D03*
Y1526976D03*
X1003044Y1605976D03*
X990245Y1582976D03*
Y1577976D03*
G54D11*
G01X80153Y1446781D02*
Y1439791D01*
X62962Y1422600D01*
G01X69500Y1742500D02*
X65000D01*
X61000Y1746500D01*
Y1769900D01*
X70400Y1779300D01*
X79700D01*
X104300Y1803900D01*
Y1821902D01*
X100287Y1825915D01*
G01X91036Y1835282D02*
Y1834717D01*
X89787Y1833468D01*
Y1830905D01*
X77159Y1818277D01*
G01X80600Y1848900D02*
X77900D01*
X71735Y1842735D01*
Y1841571D01*
X72123Y1841183D01*
G01X100287Y1825915D02*
Y1829987D01*
X100300Y1830000D01*
G01X72123Y1841183D02*
X74306Y1839000D01*
X87318D01*
X91036Y1835282D01*
G01X125700Y54400D02*
X138800D01*
X147800Y45400D01*
Y37228D01*
X162690Y22338D01*
X199538D01*
X208150Y30950D01*
Y32250D01*
G01X126000Y1466000D02*
Y1479500D01*
X128250Y1481750D01*
Y1506500D01*
G01X150200Y1628000D02*
X143500Y1634700D01*
Y1642300D01*
X131100Y1654700D01*
X126900D01*
G01X728700Y1933100D02*
Y1929300D01*
X819000Y1839000D01*
G01X771000Y1666500D02*
Y1741000D01*
X815000Y1785000D01*
G01X834750Y1823285D02*
Y1809750D01*
X815000Y1790000D01*
Y1785000D01*
G01X910500Y1734600D02*
Y1736000D01*
X903500Y1743000D01*
X894500D01*
X858500Y1779000D01*
Y1799535D01*
X834750Y1823285D01*
G01D02*
X830081Y1827954D01*
X830046D01*
X819000Y1839000D01*
X-49168Y52138D03*
X26000Y1965500D03*
X1009500Y27500D03*
X1010500Y1966000D03*
X1085741Y22661D03*
Y1967598D03*
G54D12*
G01X-106883Y-224955D02*
Y-304955D01*
G01Y-260455D02*
X1019417D01*
G01X-106883Y-304955D02*
X1019417D01*
G01X-110883Y-208955D02*
G02I-12000J0D01*
G01X-116033D02*
G02I-6850J0D01*
G01X-122883Y-224955D02*
Y-192955D01*
G01X-106883Y-208955D02*
X-138883D01*
G01X-106883Y-224955D02*
X1019417D01*
G01X7358Y629693D02*
X14830D01*
X16500Y631363D01*
G01X7358Y626544D02*
X14721D01*
X16500Y624765D01*
G01X7358Y617095D02*
X14830D01*
X16500Y618765D01*
G01X7358Y613945D02*
X14721D01*
X16500Y612166D01*
G01X7358Y604496D02*
X14830D01*
X16500Y606166D01*
G01X7358Y702134D02*
X14721D01*
X16500Y700355D01*
G01X7358Y692685D02*
X14830D01*
X16500Y694355D01*
G01X7358Y689536D02*
X14721D01*
X16500Y687757D01*
G01X7358Y680087D02*
X14830D01*
X16500Y681757D01*
G01X7358Y676937D02*
X14721D01*
X16500Y675158D01*
G01X7358Y667489D02*
X14831D01*
X16500Y669158D01*
G01X7358Y639142D02*
X14721D01*
X16500Y637363D01*
G01X7358Y651741D02*
X14259D01*
X16500Y649500D01*
G01X7358Y654890D02*
X14390D01*
X16500Y657000D01*
G01Y644530D02*
X14262Y642292D01*
X7358D01*
G01X16500Y662226D02*
X14387Y664339D01*
X7358D01*
G01Y771426D02*
X14720D01*
X16500Y769646D01*
G01X7358Y761977D02*
X14831D01*
X16500Y763646D01*
G01X7358Y758827D02*
X14721D01*
X16500Y757048D01*
G01X7358Y727331D02*
X14721D01*
X16500Y725552D01*
G01X7358Y717882D02*
X14830D01*
X16500Y719552D01*
G01X7358Y714733D02*
X14720D01*
X16500Y712953D01*
G01X7358Y705284D02*
X14831D01*
X16500Y706953D01*
G01X7358Y749378D02*
X14220D01*
X16500Y751658D01*
G01X7358Y847016D02*
X14830D01*
X16500Y848686D01*
G01X7358Y843867D02*
X14720D01*
X16500Y842087D01*
G01X7358Y834418D02*
X14831D01*
X16500Y836087D01*
G01X7358Y831268D02*
X14721D01*
X16500Y829489D01*
G01X7358Y821819D02*
X14830D01*
X16500Y823489D01*
G01X7358Y818670D02*
X14721D01*
X16500Y816891D01*
G01X7358Y809221D02*
X14830D01*
X16500Y810891D01*
G01X7358Y806071D02*
X14721D01*
X16500Y804292D01*
G01X7358Y796622D02*
X14830D01*
X16500Y798292D01*
G01X7358Y793473D02*
X14721D01*
X16500Y791694D01*
G01X7358Y784024D02*
X14830D01*
X16500Y785694D01*
G01X7358Y919457D02*
X14721D01*
X16500Y917678D01*
G01X7358Y910008D02*
X14830D01*
X16500Y911678D01*
G01X7358Y906859D02*
X14720D01*
X16500Y905079D01*
G01X7358Y897410D02*
X14831D01*
X16500Y899079D01*
G01X7358Y881662D02*
X14721D01*
X16500Y879883D01*
G01X7358Y872213D02*
X14830D01*
X16500Y873883D01*
G01X7358Y869063D02*
X14721D01*
X16500Y867284D01*
G01X7358Y859615D02*
X14831D01*
X16500Y861284D01*
G01X7358Y856465D02*
X14721D01*
X16500Y854686D01*
G01X33469Y1012371D02*
Y1029523D01*
G01D02*
Y1046675D01*
G01X16317Y1029523D02*
X33469D01*
G01D02*
X50621D01*
G01X7358Y1138355D02*
X14831D01*
X16500Y1140024D01*
G01X7358Y1122607D02*
X14721D01*
X16500Y1120828D01*
G01X7358Y1113158D02*
X14830D01*
X16500Y1114828D01*
G01X7358Y1110008D02*
X14721D01*
X16500Y1108229D01*
G01X7358Y1100559D02*
X14830D01*
X16500Y1102229D01*
G01X7358Y1210796D02*
X14720D01*
X16500Y1209016D01*
G01X7358Y1201347D02*
X14831D01*
X16500Y1203016D01*
G01X7358Y1198197D02*
X14721D01*
X16500Y1196418D01*
G01X7358Y1188748D02*
X14830D01*
X16500Y1190418D01*
G01X7358Y1185599D02*
X14721D01*
X16500Y1183820D01*
G01X7358Y1176150D02*
X14830D01*
X16500Y1177820D01*
G01X7358Y1173000D02*
X14721D01*
X16500Y1171221D01*
G01X7358Y1163552D02*
X14831D01*
X16500Y1165221D01*
G01X7358Y1160402D02*
X14721D01*
X16500Y1158623D01*
G01X7358Y1150953D02*
X14830D01*
X16500Y1152623D01*
G01X7358Y1147804D02*
X14720D01*
X16500Y1146024D01*
G01X7358Y1283237D02*
X14831D01*
X16500Y1284906D01*
G01X7358Y1280087D02*
X14721D01*
X16500Y1278308D01*
G01X7358Y1270638D02*
X14830D01*
X16500Y1272308D01*
G01X7358Y1267489D02*
X14720D01*
X16500Y1265709D01*
G01X7358Y1258040D02*
X14831D01*
X16500Y1259709D01*
G01X7358Y1254890D02*
X14721D01*
X16500Y1253111D01*
G01X7358Y1223394D02*
X14721D01*
X16500Y1221615D01*
G01X7358Y1213945D02*
X14830D01*
X16500Y1215615D01*
G01X7358Y1245441D02*
X14220D01*
X16500Y1247721D01*
G01X7358Y1355678D02*
X14831D01*
X16500Y1357347D01*
G01X7358Y1352528D02*
X14721D01*
X16500Y1350749D01*
G01X7358Y1343079D02*
X14830D01*
X16500Y1344749D01*
G01X7358Y1339930D02*
X14720D01*
X16500Y1338150D01*
G01X7358Y1330481D02*
X14831D01*
X16500Y1332150D01*
G01X7358Y1327331D02*
X14721D01*
X16500Y1325552D01*
G01X7358Y1317882D02*
X14830D01*
X16500Y1319552D01*
G01X7358Y1305284D02*
X14721D01*
X16500Y1303505D01*
G01X7358Y1295835D02*
X14830D01*
X16500Y1297505D01*
G01X7358Y1292685D02*
X14721D01*
X16500Y1290906D01*
G01X7358Y1415520D02*
X14721D01*
X16500Y1413741D01*
G01X7358Y1406071D02*
X14830D01*
X16500Y1407741D01*
G01X7358Y1402922D02*
X14720D01*
X16500Y1401142D01*
G01X7358Y1393473D02*
X14831D01*
X16500Y1395142D01*
G01X7358Y1390323D02*
X14721D01*
X16500Y1388544D01*
G01X7358Y1380874D02*
X14830D01*
X16500Y1382544D01*
G01X7358Y1377725D02*
X14721D01*
X16500Y1375946D01*
G01X7358Y1368276D02*
X14830D01*
X16500Y1369946D01*
G01X7358Y1365126D02*
X14721D01*
X16500Y1363347D01*
G01X7358Y1565126D02*
X15126D01*
X16500Y1566500D01*
G01X7358Y1561976D02*
X15024D01*
X16500Y1560500D01*
G01X7358Y1549378D02*
X15122D01*
X16500Y1548000D01*
G01X7358Y1536779D02*
X14721D01*
X16500Y1535000D01*
G01X7358Y1521031D02*
X16500D01*
G01X7358Y1527330D02*
X14830D01*
X16500Y1529000D01*
G01X7358Y1539929D02*
X14929D01*
X16500Y1541500D01*
G01X7358Y1552527D02*
X15027D01*
X16500Y1554000D01*
G01X7358Y1574574D02*
X14926D01*
X16500Y1573000D01*
G01X7358Y1634417D02*
X15083D01*
X16500Y1633000D01*
G01X7358Y1621818D02*
X14682D01*
X16500Y1620000D01*
G01X7358Y1609220D02*
X14780D01*
X16500Y1607500D01*
G01X7358Y1596622D02*
X14878D01*
X16500Y1595000D01*
G01X7358Y1587173D02*
X15173D01*
X16500Y1588500D01*
G01X7358Y1599771D02*
X14771D01*
X16500Y1601500D01*
G01X7358Y1612370D02*
X14870D01*
X16500Y1614000D01*
G01X7358Y1624968D02*
X14968D01*
X16500Y1626500D01*
G01X7358Y1647015D02*
X14985D01*
X16500Y1645500D01*
Y1644735D01*
G01Y1639845D02*
X14222Y1637567D01*
X7358D01*
G01Y1675362D02*
X14862D01*
X16500Y1677000D01*
G01X7358Y1687960D02*
X14960D01*
X16500Y1689500D01*
G01X7358Y1697409D02*
X15091D01*
X16500Y1696000D01*
G01X7358Y1710007D02*
X14507D01*
X16500Y1712000D01*
G01X7358Y1662763D02*
X14219D01*
X16500Y1665044D01*
G01Y1717462D02*
X14506Y1719456D01*
X7358D01*
G01X16500Y1683170D02*
X14859Y1684811D01*
X7358D01*
G01X16500Y1669933D02*
X14221Y1672212D01*
X7358D01*
G01Y1722606D02*
X15106D01*
X16500Y1724000D01*
G01X7358Y1766700D02*
X14800D01*
X16500Y1765000D01*
G01X7358Y1776149D02*
X14851D01*
X16500Y1774500D01*
G01X7358Y1747803D02*
X15303D01*
X16500Y1749000D01*
G01X7358Y1735204D02*
X15204D01*
X16500Y1736500D01*
G01Y1756052D02*
X15300Y1757252D01*
X7358D01*
G01X16500Y1743356D02*
X15203Y1744653D01*
X7358D01*
G01X16500Y1730658D02*
X15103Y1732055D01*
X7358D01*
G01X382200Y81500D02*
X378300Y85400D01*
X312400D01*
X283000Y56000D01*
X166900D01*
X152400Y41500D01*
G01X231917Y-224955D02*
Y-304955D01*
G01X252538Y1490152D02*
X269690D01*
G01Y1473000D02*
Y1490152D01*
G01D02*
Y1507304D01*
G01Y1490152D02*
X286842D01*
G01X369417Y-224955D02*
Y-304955D01*
G01X484417Y-224955D02*
Y-304955D01*
G01X651917Y-224955D02*
Y-304955D01*
G01X821917Y-224955D02*
Y-304955D01*
G01X876500Y648000D02*
X899087D01*
X901441Y650354D01*
G01Y1055866D02*
X899075Y1053500D01*
X876500D01*
G01Y1459000D02*
X899063D01*
X901441Y1461378D01*
G01X913000Y1717750D02*
X910500Y1720250D01*
Y1724700D01*
G01X876000Y1864000D02*
X898551D01*
X901441Y1866890D01*
G01X919250Y1711500D02*
X913000Y1717750D01*
G01X1019417Y-224955D02*
Y-304955D01*
G01X1047417Y-208955D02*
G02I-12000J0D01*
G01X1042267D02*
G02I-6850J0D01*
G01X1035417Y-224955D02*
Y-192955D01*
G01X1051417Y-208955D02*
X1019417D01*
G01X1008244Y1666102D02*
X995000D01*
X20000Y40000D03*
Y20000D03*
X5500Y40982D03*
Y20982D03*
X10018Y5500D03*
X30018D03*
X20000Y80000D03*
Y100000D03*
Y120000D03*
Y60000D03*
X5500Y120982D03*
Y100982D03*
Y80982D03*
Y60982D03*
X20000Y160000D03*
Y180000D03*
Y140000D03*
X5500Y180982D03*
Y160982D03*
Y140982D03*
X20000Y240000D03*
Y200000D03*
Y220000D03*
X5500Y260982D03*
Y240982D03*
Y220982D03*
Y200982D03*
Y320982D03*
Y300982D03*
Y280982D03*
X27500Y380000D03*
X20000D03*
Y400000D03*
X5500Y400982D03*
Y380982D03*
Y360982D03*
Y340982D03*
X20000Y340000D03*
X27000Y440000D03*
X20000Y460000D03*
Y440000D03*
Y480000D03*
Y420000D03*
X5500Y480982D03*
Y460982D03*
Y440982D03*
Y420982D03*
X27500Y540000D03*
Y553500D03*
X20000Y540000D03*
Y500000D03*
Y520000D03*
X5500Y540982D03*
Y520982D03*
Y500982D03*
X24500Y624897D03*
Y612249D03*
Y619093D03*
Y606544D03*
Y599700D03*
X16500Y624765D03*
Y618765D03*
Y612166D03*
Y606166D03*
Y598197D03*
X20000Y607620D03*
Y610820D03*
Y620218D03*
Y623418D03*
X27529Y601522D03*
Y604722D03*
Y614071D03*
Y617271D03*
Y626719D03*
Y629919D03*
X24500Y700488D03*
Y694733D03*
Y687889D03*
Y675291D03*
Y682135D03*
Y669537D03*
Y662693D03*
Y637496D03*
Y644340D03*
Y631741D03*
X16500Y700355D03*
Y694355D03*
Y687757D03*
Y681757D03*
Y675158D03*
Y669158D03*
Y662226D03*
Y657000D03*
Y649500D03*
Y644530D03*
Y637363D03*
Y631363D03*
X20000Y658013D03*
Y661213D03*
Y670612D03*
Y673812D03*
Y683210D03*
Y686410D03*
Y632817D03*
Y636017D03*
Y695809D03*
Y699009D03*
Y645415D03*
Y648615D03*
X27529Y664515D03*
Y667715D03*
Y677113D03*
Y680313D03*
Y689711D03*
Y692911D03*
Y702310D03*
Y639318D03*
Y642518D03*
X24500Y769579D03*
Y763825D03*
Y756981D03*
Y725485D03*
Y732329D03*
Y719730D03*
Y712886D03*
Y707332D03*
X16500Y769646D03*
Y763646D03*
Y757048D03*
Y725552D03*
Y719552D03*
Y712953D03*
Y706953D03*
Y751658D03*
Y732500D03*
X20000Y708407D03*
Y711607D03*
Y721006D03*
Y724206D03*
Y752502D03*
Y755702D03*
Y765100D03*
Y768300D03*
X27529Y714708D03*
Y717908D03*
Y727307D03*
Y730507D03*
Y758803D03*
Y762003D03*
Y705510D03*
Y771401D03*
Y774601D03*
X27699Y737535D03*
X24500Y848664D03*
Y841820D03*
Y836266D03*
Y829422D03*
Y816823D03*
Y823667D03*
Y804225D03*
Y811069D03*
Y798470D03*
Y791626D03*
Y776423D03*
X16500Y848686D03*
Y842087D03*
Y836087D03*
Y829489D03*
Y823489D03*
Y816891D03*
Y810891D03*
Y804292D03*
Y798292D03*
Y791694D03*
Y785694D03*
Y777725D03*
X20000Y837541D03*
Y840741D03*
Y787147D03*
Y790347D03*
Y799746D03*
Y802946D03*
Y812344D03*
Y815544D03*
Y824943D03*
Y828143D03*
X27529Y843642D03*
Y846842D03*
Y793448D03*
Y796648D03*
Y806047D03*
Y809247D03*
Y818645D03*
Y821845D03*
Y831244D03*
Y834444D03*
X24500Y911856D03*
Y905012D03*
Y892414D03*
Y899258D03*
Y886509D03*
Y879665D03*
Y867017D03*
Y873861D03*
Y854419D03*
Y861263D03*
X16500Y917678D03*
Y911678D03*
Y905079D03*
Y899079D03*
Y879883D03*
Y873883D03*
Y867284D03*
Y861284D03*
Y854686D03*
Y889500D03*
X20000Y900533D03*
Y903733D03*
Y850139D03*
Y853339D03*
Y913132D03*
Y916332D03*
Y862738D03*
Y865938D03*
Y875336D03*
Y878536D03*
X27529Y894236D03*
Y897436D03*
Y856241D03*
Y859441D03*
Y906834D03*
Y910034D03*
Y868839D03*
Y872039D03*
Y881487D03*
Y884687D03*
X34872Y890906D03*
X36000Y960000D03*
X20000Y980000D03*
Y960000D03*
Y940000D03*
X16000Y931000D03*
X34500Y925000D03*
X5500Y980299D03*
X30000Y991000D03*
X36500Y999500D03*
X5500Y1040299D03*
Y1020299D03*
Y1000299D03*
X23291Y1062791D03*
X24500Y1133365D03*
Y1102601D03*
Y1095769D03*
Y1108368D03*
Y1115200D03*
X16500Y1140024D03*
Y1120828D03*
Y1114828D03*
Y1108229D03*
Y1102229D03*
Y1133500D03*
Y1094260D03*
X31707Y1086000D03*
X20000Y1103683D03*
Y1106883D03*
Y1116281D03*
Y1119481D03*
X27529Y1135181D03*
Y1138381D03*
Y1097585D03*
Y1100785D03*
Y1110184D03*
Y1113384D03*
X32335Y1122002D03*
X37396Y1130912D03*
X33971Y1131741D03*
X24500Y1208955D03*
Y1196357D03*
Y1203189D03*
Y1183758D03*
Y1190590D03*
Y1171160D03*
Y1177992D03*
Y1165394D03*
Y1158562D03*
Y1152795D03*
Y1145963D03*
Y1140197D03*
X16500Y1209016D03*
Y1203016D03*
Y1196418D03*
Y1190418D03*
Y1183820D03*
Y1177820D03*
Y1171221D03*
Y1165221D03*
Y1158623D03*
Y1152623D03*
Y1146024D03*
X20000Y1141478D03*
Y1144678D03*
Y1191872D03*
Y1195072D03*
Y1154076D03*
Y1157276D03*
Y1204470D03*
Y1207670D03*
Y1166675D03*
Y1169875D03*
Y1179273D03*
Y1182473D03*
X27529Y1185574D03*
Y1188774D03*
Y1147779D03*
Y1150979D03*
Y1198173D03*
Y1201373D03*
Y1160378D03*
Y1163578D03*
Y1210771D03*
Y1172976D03*
Y1176176D03*
X24500Y1285079D03*
Y1278247D03*
Y1272480D03*
Y1265648D03*
Y1259882D03*
Y1253050D03*
Y1228386D03*
Y1221554D03*
Y1215787D03*
X16500Y1284906D03*
Y1278308D03*
Y1272308D03*
Y1265709D03*
Y1259709D03*
Y1253111D03*
Y1247721D03*
Y1221615D03*
Y1215615D03*
Y1228500D03*
X20000Y1261163D03*
Y1264363D03*
Y1273761D03*
Y1276961D03*
Y1217069D03*
Y1220269D03*
Y1248565D03*
Y1251765D03*
X27529Y1254866D03*
Y1258066D03*
Y1267464D03*
Y1270664D03*
Y1280063D03*
Y1283263D03*
Y1213971D03*
Y1223370D03*
Y1226570D03*
X33201Y1230674D03*
X32959Y1234478D03*
X36000Y1236000D03*
X24500Y1357720D03*
Y1350888D03*
Y1345121D03*
Y1338289D03*
Y1332523D03*
Y1325691D03*
Y1319924D03*
Y1313092D03*
Y1290845D03*
Y1297677D03*
X34000Y1321000D03*
X16500Y1357347D03*
Y1350749D03*
Y1344749D03*
Y1338150D03*
Y1332150D03*
Y1325552D03*
Y1319552D03*
Y1303505D03*
Y1297505D03*
Y1290906D03*
X16417Y1311583D03*
X20000Y1321006D03*
Y1324206D03*
Y1333604D03*
Y1336804D03*
Y1346202D03*
Y1349402D03*
Y1286360D03*
Y1289560D03*
Y1298958D03*
Y1302158D03*
X27529Y1314908D03*
Y1318108D03*
Y1327507D03*
Y1330707D03*
Y1340105D03*
Y1343305D03*
Y1352704D03*
Y1355904D03*
Y1292661D03*
Y1295861D03*
X36170Y1308434D03*
X33699Y1301782D03*
X26500Y1305121D03*
X33938Y1311000D03*
X38500D03*
X30000Y1305000D03*
X30700Y1308600D03*
X24500Y1401081D03*
Y1407913D03*
Y1388483D03*
Y1395315D03*
Y1375884D03*
Y1382716D03*
Y1370118D03*
Y1363286D03*
X21000Y1424500D03*
X16500Y1413741D03*
Y1407741D03*
Y1401142D03*
Y1395142D03*
Y1388544D03*
Y1382544D03*
Y1375946D03*
Y1369946D03*
Y1363347D03*
X20000Y1371399D03*
Y1374599D03*
Y1383998D03*
Y1387198D03*
Y1396596D03*
Y1399796D03*
Y1358801D03*
Y1362001D03*
Y1409195D03*
Y1412395D03*
X27529Y1365102D03*
Y1368302D03*
Y1377700D03*
Y1380900D03*
Y1390299D03*
Y1393499D03*
Y1402897D03*
Y1406097D03*
X27000Y1417500D03*
X32500Y1417600D03*
X22000Y1487000D03*
X37000Y1443500D03*
X30500Y1463500D03*
X28000Y1444000D03*
X36401Y1521623D03*
X32801D03*
X24500Y1560197D03*
Y1566907D03*
Y1547598D03*
Y1554308D03*
Y1522401D03*
Y1529111D03*
Y1541710D03*
Y1535000D03*
X16500Y1573000D03*
Y1566500D03*
Y1560500D03*
Y1554000D03*
Y1548000D03*
Y1541500D03*
Y1535000D03*
Y1529000D03*
Y1521031D03*
Y1512500D03*
X20000Y1530454D03*
Y1533654D03*
Y1543052D03*
Y1546252D03*
Y1555650D03*
Y1558850D03*
Y1568249D03*
Y1571449D03*
X27529Y1524156D03*
Y1527356D03*
Y1536755D03*
Y1539955D03*
Y1549353D03*
Y1552553D03*
Y1561952D03*
Y1565152D03*
X33001Y1518123D03*
X36201D03*
X24500Y1632638D03*
Y1639348D03*
Y1626749D03*
Y1620039D03*
Y1614151D03*
Y1607441D03*
Y1601552D03*
Y1594842D03*
Y1588954D03*
Y1582244D03*
X16500Y1644735D03*
Y1639845D03*
Y1633000D03*
Y1626500D03*
Y1620000D03*
Y1614000D03*
Y1607500D03*
Y1601500D03*
Y1595000D03*
Y1588500D03*
Y1582500D03*
X20000Y1640690D03*
Y1643890D03*
Y1593496D03*
Y1590296D03*
Y1606094D03*
Y1602894D03*
Y1618693D03*
Y1615493D03*
Y1631291D03*
Y1628091D03*
X27529Y1634393D03*
Y1637593D03*
Y1587199D03*
Y1583999D03*
Y1599797D03*
Y1596597D03*
Y1612396D03*
Y1609196D03*
Y1624994D03*
Y1621794D03*
X24500Y1717868D03*
Y1702531D03*
Y1695821D03*
Y1689932D03*
Y1683222D03*
Y1677334D03*
Y1670624D03*
X16500Y1669933D03*
Y1677000D03*
Y1683170D03*
Y1689500D03*
Y1696000D03*
Y1702500D03*
Y1712000D03*
Y1717462D03*
Y1665044D03*
X20000Y1716331D03*
Y1713131D03*
Y1665887D03*
Y1669087D03*
Y1678485D03*
Y1681685D03*
Y1691083D03*
Y1694283D03*
X27529Y1719623D03*
Y1672379D03*
Y1675579D03*
Y1684977D03*
Y1688177D03*
Y1697576D03*
Y1700776D03*
X35900Y1706000D03*
X34224Y1709000D03*
X38000Y1715000D03*
X31981Y1768323D03*
X24500Y1755663D03*
Y1762373D03*
Y1743065D03*
Y1749775D03*
Y1730466D03*
Y1737176D03*
Y1724578D03*
X22219Y1768323D03*
X16500Y1749000D03*
Y1756052D03*
Y1765000D03*
Y1774500D03*
Y1784000D03*
Y1790500D03*
Y1724000D03*
Y1730658D03*
Y1736500D03*
Y1743356D03*
X20000Y1728929D03*
Y1725729D03*
Y1741528D03*
Y1738328D03*
Y1754126D03*
Y1750926D03*
X27529Y1722823D03*
Y1735421D03*
Y1732221D03*
Y1748020D03*
Y1744820D03*
Y1760618D03*
Y1757418D03*
X25500Y1769558D03*
X28700D03*
X39500Y1823300D03*
X39400Y1819900D03*
X38400Y1846750D03*
X38300Y1859050D03*
X5500Y1880685D03*
Y1888685D03*
X38500Y1871350D03*
X38200Y1883800D03*
X19974Y1943969D03*
X33700Y1960300D03*
X20000Y1960000D03*
Y1980000D03*
X32559Y1986626D03*
X12559D03*
X5500Y1973685D03*
Y1953685D03*
X30200Y1970300D03*
X40000Y40000D03*
Y20000D03*
X90018Y5500D03*
X110018D03*
X50018D03*
X70018D03*
X109038Y62310D03*
X109000Y81106D03*
X109160Y105900D03*
X60000Y80000D03*
X40000D03*
Y100000D03*
Y120000D03*
Y60000D03*
X109038Y68476D03*
X109000Y87476D03*
X109160Y100476D03*
X96000Y114212D03*
Y107913D03*
Y98464D03*
Y89015D03*
Y79567D03*
Y70118D03*
Y60868D03*
X96100Y52300D03*
X72500Y91161D03*
Y86161D03*
X71000Y58000D03*
X96000Y119000D03*
X99500Y95940D03*
Y91540D03*
Y77042D03*
Y72642D03*
Y58244D03*
Y53844D03*
X105000Y104788D03*
Y101588D03*
Y85891D03*
Y82691D03*
Y66993D03*
Y63793D03*
X72500Y61161D03*
X67500Y124088D03*
X108917Y150188D03*
X100000Y180000D03*
X99800Y194200D03*
X40000Y160000D03*
Y180000D03*
Y140000D03*
X67500Y135830D03*
X108917Y156976D03*
X72500Y166161D03*
X96000Y158307D03*
X72500Y151161D03*
X96000Y148858D03*
X72500Y136161D03*
X96000Y139409D03*
Y134000D03*
Y123661D03*
X104000Y125000D03*
X71000Y125236D03*
X68000Y128359D03*
Y131559D03*
X99500Y146333D03*
Y141933D03*
X105000Y155182D03*
Y151982D03*
X85250Y247238D03*
X80000Y200000D03*
X77306Y259381D03*
X40000Y240000D03*
Y200000D03*
Y220000D03*
X99300Y201000D03*
X60306Y212338D03*
X80153Y230246D03*
X85427Y239715D03*
X100400Y208300D03*
X70500Y242988D03*
X80300Y234465D03*
X97400Y220200D03*
X97000Y296500D03*
X111500Y276000D03*
X84500Y315000D03*
X67000Y269000D03*
X66512Y287899D03*
X66610Y295956D03*
X56024Y292549D03*
X97400Y366600D03*
X95849Y361564D03*
X46487Y360400D03*
X48822Y393916D03*
X100400Y406000D03*
X104400D03*
X107900D03*
X96900D03*
X110000Y362500D03*
X106500D03*
X110000Y366000D03*
X106500D03*
X92700Y358400D03*
X52066Y370649D03*
X109044Y467822D03*
X51500Y469000D03*
X112600Y442500D03*
X98300Y443400D03*
X109044Y473988D03*
X96000Y485079D03*
Y475630D03*
Y466181D03*
Y456732D03*
X71000Y463500D03*
X112600Y439000D03*
X99500Y482554D03*
Y478154D03*
Y463656D03*
Y459256D03*
X105000Y472505D03*
Y469305D03*
X72500Y466673D03*
X109000Y486618D03*
X109138Y505912D03*
X67500Y529600D03*
X108917Y555700D03*
X67500Y541342D03*
X109000Y492988D03*
X109138Y511488D03*
X72500Y556673D03*
X96000Y554369D03*
X72500Y541673D03*
X96000Y544921D03*
Y539500D03*
Y529173D03*
Y519724D03*
Y513425D03*
Y503976D03*
Y494527D03*
X72500Y496673D03*
Y491673D03*
X104000Y531000D03*
X71000Y530748D03*
X96000Y524000D03*
X68000Y533871D03*
Y537071D03*
X99500Y551845D03*
Y547445D03*
Y501452D03*
Y497052D03*
X105000Y557494D03*
Y510300D03*
Y507100D03*
Y491403D03*
Y488203D03*
X71000Y524464D03*
X99900Y582400D03*
X61100Y600100D03*
X61900Y584300D03*
X72900Y605400D03*
X94700Y599800D03*
X80000Y600000D03*
X108917Y562488D03*
X72500Y571673D03*
X96000Y563819D03*
X89400Y603250D03*
X95900Y605500D03*
X62426Y607740D03*
X105000Y560694D03*
X88600Y623300D03*
X85250Y652750D03*
X61500Y682500D03*
X59000Y659500D03*
X49000Y638000D03*
X76500Y665000D03*
X80153Y635758D03*
X85223Y645227D03*
X70500Y648500D03*
X48000Y649500D03*
X46500Y653500D03*
X80300Y639977D03*
X50560Y653500D03*
X97000Y772100D03*
X87075Y768250D03*
X102500Y737500D03*
X83200Y768300D03*
X76000Y706500D03*
X62000Y736500D03*
X61500Y748000D03*
X51500Y730500D03*
Y757500D03*
X106500Y771500D03*
X110000D03*
Y768000D03*
X106500D03*
X86900Y774750D03*
X49500Y771000D03*
X67500Y822500D03*
X63100Y788800D03*
X73500Y779500D03*
X100600Y811300D03*
X104600D03*
X108100D03*
X97100D03*
X112500Y848700D03*
Y845200D03*
X80215Y777137D03*
X109040Y873334D03*
X109000Y892130D03*
X109187Y911424D03*
X51000Y913500D03*
X63500Y899000D03*
X65500Y867500D03*
X98300Y850400D03*
X109040Y879500D03*
X109000Y898500D03*
X109187Y917000D03*
X96000Y918937D03*
Y909488D03*
Y900039D03*
Y890591D03*
Y881142D03*
Y871692D03*
Y862244D03*
X72500Y902185D03*
Y897185D03*
X71000Y869000D03*
X47500Y901500D03*
X99500Y906964D03*
Y902564D03*
Y888066D03*
Y883666D03*
Y869168D03*
Y864768D03*
X105000Y915812D03*
Y912612D03*
Y896915D03*
Y893715D03*
Y878017D03*
Y874817D03*
X72500Y872185D03*
X67500Y935111D03*
X109000Y961212D03*
X67000Y953500D03*
X96532Y977682D03*
X107400Y994000D03*
X67500Y946855D03*
X109000Y968000D03*
X72500Y977185D03*
X96000Y969331D03*
X72500Y962185D03*
X96000Y959882D03*
X72500Y947185D03*
X96000Y950433D03*
Y945000D03*
Y934685D03*
Y925236D03*
X104000Y936000D03*
X96000Y930000D03*
X71000Y936260D03*
X68000Y939383D03*
Y942583D03*
X99500Y957357D03*
Y952957D03*
X105000Y966206D03*
Y963006D03*
X65500Y927500D03*
X71000Y925500D03*
X99600Y1001400D03*
X102403Y1058209D03*
X103200Y1042500D03*
X83248Y1059636D03*
X93000Y1005700D03*
X81689Y1039600D03*
X77750Y1056750D03*
X96500Y1011200D03*
X64037Y1016654D03*
X74000Y1047500D03*
X41000Y1057500D03*
X81689Y1049400D03*
X106100Y1030000D03*
X71000Y1109000D03*
X42286Y1089500D03*
Y1085500D03*
X67090Y1070360D03*
X41608Y1125065D03*
X39959Y1128308D03*
X96100Y1176700D03*
X87900Y1173300D03*
X111500Y1145000D03*
X75000Y1182500D03*
X41500Y1165500D03*
Y1178000D03*
X67500Y1191500D03*
X110000Y1173500D03*
X106500D03*
X110000Y1177000D03*
X106500D03*
X88500Y1177300D03*
X40097Y1142513D03*
X85300Y1182000D03*
X109040Y1278846D03*
X81500Y1213000D03*
X99100Y1219800D03*
X104500Y1217000D03*
X108000D03*
X95700Y1219700D03*
X112600Y1254300D03*
X98300Y1255900D03*
X109040Y1285012D03*
X96000Y1277205D03*
Y1267756D03*
X71000Y1274500D03*
X112600Y1250800D03*
X99500Y1274680D03*
Y1270280D03*
X105000Y1283529D03*
Y1280329D03*
X72500Y1277697D03*
X109000Y1297642D03*
X109133Y1316936D03*
X67500Y1340624D03*
X64000Y1328500D03*
X58500Y1320500D03*
X67500Y1352366D03*
X109000Y1304012D03*
X109133Y1322512D03*
X72500Y1352697D03*
X96000Y1355945D03*
Y1350500D03*
Y1340197D03*
Y1330748D03*
Y1324449D03*
Y1315000D03*
Y1305551D03*
Y1296103D03*
Y1286654D03*
X72500Y1307697D03*
Y1302697D03*
X104000Y1341000D03*
X71000Y1341772D03*
X96000Y1335000D03*
X68000Y1344895D03*
Y1348095D03*
X99500Y1312476D03*
Y1308076D03*
Y1293578D03*
Y1289178D03*
X105000Y1321324D03*
Y1318124D03*
Y1302427D03*
Y1299227D03*
X71000Y1335488D03*
X58900Y1317000D03*
X109000Y1366724D03*
Y1373512D03*
X70838Y1384165D03*
X96000Y1374843D03*
X72285Y1365633D03*
X96000Y1365393D03*
X96250Y1414400D03*
X62962Y1422600D03*
X100000Y1423000D03*
X99900Y1419600D03*
X99500Y1362869D03*
Y1358469D03*
X105000Y1371718D03*
Y1368518D03*
X48000Y1482000D03*
X82748Y1465560D03*
X80000Y1480000D03*
X109500Y1486000D03*
X110000Y1470000D03*
X99300Y1431200D03*
X82748Y1455148D03*
X76750Y1462762D03*
X80153Y1446781D03*
X73000Y1455100D03*
X69365Y1474719D03*
X80300Y1451000D03*
X88076Y1575924D03*
X90500Y1521500D03*
X96000Y1541100D03*
X72000Y1551500D03*
X72100Y1536400D03*
Y1509900D03*
X48000Y1505500D03*
X91125Y1565900D03*
X105700Y1548200D03*
X82005Y1540500D03*
X85808D03*
X110500Y1573200D03*
X107000D03*
X103500D03*
X80465Y1570120D03*
X109050Y1540600D03*
X46893Y1519979D03*
X47368Y1527323D03*
X42644Y1521957D03*
X46845Y1514264D03*
X43000Y1526000D03*
X42960Y1517408D03*
X64500Y1581500D03*
X100500Y1622500D03*
X104500D03*
X108000D03*
X97000D03*
X40500Y1608500D03*
X107000Y1576700D03*
X103500D03*
X110500D03*
X42919Y1583175D03*
X64525Y1591016D03*
X109040Y1684358D03*
X109000Y1703154D03*
X66500Y1694000D03*
X68000Y1651500D03*
X98600Y1659800D03*
X109040Y1690524D03*
X109000Y1709524D03*
X96000Y1701615D03*
Y1711063D03*
Y1673268D03*
X72500Y1708209D03*
X96000Y1682716D03*
Y1692166D03*
X71000Y1680000D03*
X72500Y1713209D03*
X96000Y1720512D03*
X99500Y1713588D03*
Y1717988D03*
Y1694690D03*
Y1699090D03*
Y1675792D03*
Y1680192D03*
X105000Y1704739D03*
Y1707939D03*
Y1685841D03*
Y1689041D03*
X72500Y1683209D03*
X51635Y1665355D03*
X66400Y1706900D03*
X109137Y1722448D03*
X67500Y1757886D03*
X109030Y1778736D03*
X100000Y1780000D03*
X67500Y1746128D03*
X109137Y1728024D03*
X109030Y1772524D03*
X96000Y1729961D03*
Y1736260D03*
Y1745109D03*
Y1755158D03*
Y1761457D03*
Y1770906D03*
X72500Y1758209D03*
Y1773209D03*
Y1788209D03*
X96000Y1780355D03*
X100000Y1759000D03*
X71000Y1747284D03*
X104000Y1747800D03*
X68000Y1750407D03*
Y1753607D03*
X99500Y1763981D03*
Y1768381D03*
X105000Y1774030D03*
Y1777230D03*
Y1723636D03*
Y1726836D03*
X67000Y1738000D03*
X71015D03*
X93600Y1848200D03*
X45100Y1850800D03*
X42300Y1846750D03*
X42200Y1859050D03*
X45200Y1839300D03*
Y1843300D03*
Y1854700D03*
X40800Y1832300D03*
Y1827300D03*
X76975Y1864000D03*
X100300Y1820800D03*
X77159Y1818277D03*
X91036Y1835282D03*
X72123Y1841183D03*
X100287Y1825915D03*
X100300Y1830000D03*
X80600Y1848900D03*
X98000Y1848800D03*
X85000Y1817100D03*
X74100Y1796200D03*
X67800Y1855200D03*
X93625Y1802200D03*
X52000Y1877500D03*
X100000Y1928000D03*
X80000D03*
X60000D03*
X74300Y1900000D03*
X107543Y1898024D03*
X111000Y1879570D03*
X100100Y1896300D03*
X80000Y1920000D03*
X60000D03*
Y1900000D03*
X44000D03*
X40556Y1917072D03*
X40000Y1940000D03*
X52000Y1887500D03*
X41700Y1883700D03*
X42100Y1871350D03*
X112366Y1883985D03*
X46868Y1887765D03*
X60897Y1885848D03*
X48000Y1877500D03*
X110700Y1974100D03*
X80000Y1980000D03*
X100300Y1980900D03*
X71666Y1961325D03*
X43935Y1957215D03*
X56875Y1954250D03*
X40000Y1980000D03*
X112559Y1986626D03*
X92559D03*
X72559D03*
X52559D03*
X94700Y1974100D03*
X98800D03*
X103300D03*
X107000D03*
X80400Y1957900D03*
X73400D03*
X76900D03*
X87500Y1954300D03*
X80400Y1954400D03*
X83900D03*
X73400D03*
X76900D03*
X57800Y1961800D03*
X170034Y31475D03*
X155018Y5500D03*
X170018D03*
X116600Y46800D03*
X177300Y39000D03*
X180800D03*
X184300D03*
X180800Y35500D03*
X177300D03*
X184300D03*
X152400Y41500D03*
X180000Y80000D03*
X160000D03*
X140000D03*
X154700Y65000D03*
X150200D03*
X141700Y64900D03*
X138200D03*
X131700Y61300D03*
X128200D03*
X121600Y54700D03*
X184461Y103368D03*
X125700Y54400D03*
X179147Y137913D03*
X180000Y180000D03*
X124000Y135859D03*
Y124059D03*
X147125Y160500D03*
X158300Y135200D03*
X150557Y142854D03*
X167298Y147703D03*
X159500Y181000D03*
X124000Y128359D03*
Y131559D03*
X167298Y151203D03*
X114579Y137775D03*
X154875Y160500D03*
X135064Y213390D03*
X134941Y264178D03*
X135500Y200500D03*
X125500Y265500D03*
X132500Y236000D03*
X128500Y248000D03*
X176492Y231103D03*
X180100Y231095D03*
X135064Y219602D03*
X171595Y203917D03*
X148095Y211771D03*
X171595Y218917D03*
X148095Y221220D03*
X171595Y233917D03*
X148095Y230669D03*
Y236968D03*
Y246417D03*
Y255866D03*
Y262165D03*
X140000Y247500D03*
X173095Y244842D03*
X148000Y241500D03*
X180000Y235394D03*
X176800D03*
X144595Y223745D03*
Y228145D03*
X139095Y214896D03*
Y218096D03*
Y265290D03*
X172900Y249400D03*
X143600Y252100D03*
X129000Y255500D03*
X135095Y288972D03*
X134995Y301768D03*
X126000Y293000D03*
X125000Y312000D03*
X145800Y332400D03*
X131300D03*
X134941Y269602D03*
X135095Y282602D03*
X134995Y307602D03*
X148095Y271614D03*
Y281063D03*
Y290511D03*
Y299960D03*
Y309409D03*
Y318858D03*
X171595Y278917D03*
Y283917D03*
X173000Y312500D03*
X131300Y335900D03*
X126445Y338300D03*
X114295D03*
X144595Y274138D03*
Y278538D03*
Y293036D03*
Y297436D03*
Y311934D03*
Y316334D03*
X139095Y268490D03*
Y284187D03*
Y287387D03*
Y303085D03*
Y306285D03*
X171595Y308917D03*
X145900Y408500D03*
X119159Y405100D03*
X124466Y370025D03*
X143500Y370000D03*
X147000D03*
X139500D03*
X136000D03*
X134000Y409500D03*
X137500D03*
X130500D03*
X127000D03*
X117000Y362500D03*
Y366000D03*
X113500Y362500D03*
Y366000D03*
X173800Y379800D03*
X157200Y412000D03*
X158500Y408000D03*
X148700Y413400D03*
X180000Y480000D03*
X163500Y423000D03*
X180000Y460000D03*
X120000D03*
X140000Y480000D03*
Y460000D03*
X160000Y440000D03*
X140000D03*
X120800Y438000D03*
X127000Y413000D03*
X130500D03*
X134000D03*
X137500D03*
X170500Y478500D03*
X125300Y438000D03*
X157500Y551200D03*
X160000Y520000D03*
X180000D03*
X124000Y541373D03*
Y529573D03*
X165138Y536500D03*
X174000Y553500D03*
X157750Y541250D03*
X184500Y553500D03*
X124000Y533873D03*
Y537073D03*
X157750Y544750D03*
X135095Y625402D03*
X158500Y569500D03*
X131500Y610500D03*
X180000Y620000D03*
Y580000D03*
X139500Y600400D03*
X180000Y600000D03*
X135095Y618614D03*
X171595Y609429D03*
X148095Y617283D03*
X171595Y624429D03*
X148095Y626732D03*
X132350Y563750D03*
X159600Y581400D03*
X155500Y574000D03*
X144595Y629257D03*
X139095Y620408D03*
Y623608D03*
X150850Y574350D03*
X134941Y669690D03*
X135095Y694484D03*
X176492Y636617D03*
X180308D03*
X134941Y675114D03*
X135095Y688114D03*
X171895Y639429D03*
X148095Y636181D03*
Y642480D03*
Y651929D03*
Y661378D03*
Y667677D03*
Y677126D03*
Y686575D03*
Y696023D03*
X171595Y684429D03*
Y689429D03*
X140000Y654000D03*
X148000Y648000D03*
X173095Y650354D03*
X180000Y640906D03*
X176800D03*
X144595Y633657D03*
Y679650D03*
Y684050D03*
Y698548D03*
Y702948D03*
X139095Y670802D03*
Y674002D03*
Y689699D03*
Y692899D03*
X173000Y655200D03*
X134993Y707280D03*
X124966Y775525D03*
X125500Y719000D03*
X180000Y720000D03*
X136100Y775600D03*
X139600D03*
X147100D03*
X143600D03*
X145800Y737100D03*
X131400Y738200D03*
X134993Y713114D03*
X148095Y705472D03*
Y714921D03*
Y724370D03*
X173000Y718000D03*
X131400Y741700D03*
X122445Y743800D03*
X117000Y771500D03*
Y768000D03*
X113500Y771500D03*
Y768000D03*
X117945Y743800D03*
X144595Y717446D03*
Y721846D03*
X139095Y708597D03*
Y711797D03*
X171595Y714429D03*
X148600Y818700D03*
X147100Y814200D03*
X119534Y810975D03*
X116000Y814500D03*
X122251Y842400D03*
X127000Y818500D03*
X130500D03*
X134000D03*
X137500D03*
X134000Y815000D03*
X137500D03*
X130500D03*
X127000D03*
X156800Y816000D03*
X126800Y842500D03*
X143800Y807400D03*
X160000Y880000D03*
X140000Y900000D03*
X182000Y949000D03*
X180000Y980000D03*
X167000Y945909D03*
Y935909D03*
X178000Y960000D03*
X162200Y988000D03*
X161095Y980622D03*
X167000Y939309D03*
Y942509D03*
X174500Y960000D03*
X157200Y950800D03*
X155900Y954200D03*
X157000Y957500D03*
X161200Y946100D03*
X161700Y950800D03*
X135095Y1030914D03*
X180000Y1000000D03*
X176492Y1042129D03*
X180308D03*
X135095Y1024126D03*
X171595Y1014941D03*
X148095Y1022795D03*
X171595Y1029941D03*
X148095Y1032244D03*
X171595Y1044941D03*
X148095Y1041693D03*
Y1047992D03*
Y1057441D03*
Y1066890D03*
X140000Y1059500D03*
X129000Y1051500D03*
X173095Y1055866D03*
X148000Y1053500D03*
X180000Y1046418D03*
X176800D03*
X144595Y1034769D03*
Y1039169D03*
X139095Y1025920D03*
Y1029120D03*
X137500Y1014500D03*
X173000Y1060400D03*
X139300Y1067000D03*
X134941Y1075202D03*
X135095Y1099996D03*
X135001Y1112792D03*
X180000Y1140000D03*
X129500Y1084500D03*
X122500Y1107000D03*
X123500Y1123500D03*
X180000Y1120000D03*
Y1100000D03*
Y1080000D03*
X147800Y1140000D03*
X134941Y1080626D03*
X135095Y1093626D03*
X135001Y1118626D03*
X148095Y1073189D03*
Y1082638D03*
Y1092087D03*
Y1101535D03*
Y1110984D03*
Y1120433D03*
Y1129882D03*
X171595Y1089941D03*
Y1094941D03*
X173000Y1123500D03*
X144595Y1085162D03*
Y1089562D03*
Y1104060D03*
Y1108460D03*
Y1122958D03*
Y1127358D03*
X139095Y1076314D03*
Y1079514D03*
Y1095211D03*
Y1098411D03*
Y1114109D03*
Y1117309D03*
X171595Y1119941D03*
X124100Y1181025D03*
X143500Y1180400D03*
X147000D03*
X139500D03*
X136000D03*
X131500Y1143200D03*
Y1146700D03*
X122400Y1149200D03*
X117000Y1173500D03*
Y1177000D03*
X113500Y1173500D03*
Y1177000D03*
X117900Y1149200D03*
X146700Y1219600D03*
X119534Y1216475D03*
X157325Y1223850D03*
X120000Y1280000D03*
X140000D03*
X160000D03*
X180000D03*
X120000Y1220000D03*
X180000D03*
X118250Y1252050D03*
X127000Y1224000D03*
X130500Y1220500D03*
Y1224000D03*
X134000D03*
X137500D03*
X134000Y1220500D03*
X137500D03*
X127000D03*
X158052Y1216052D03*
X129150Y1252050D03*
X179147Y1353048D03*
X160000Y1340000D03*
X180000D03*
X140000D03*
Y1300000D03*
X160000D03*
X180000D03*
X129500Y1352321D03*
Y1340521D03*
X147956Y1347802D03*
X129500Y1344821D03*
Y1348021D03*
X154709Y1344513D03*
X121320Y1425396D03*
X117690Y1397168D03*
X143087Y1403623D03*
X180000Y1400000D03*
Y1420000D03*
X135095Y1429638D03*
X171595Y1420453D03*
X148095Y1428307D03*
X160000Y1360000D03*
X151125Y1376608D03*
X140125Y1381300D03*
X167301Y1363238D03*
Y1366838D03*
X158875Y1376100D03*
X135095Y1436426D03*
X134935Y1480714D03*
X126916Y1447364D03*
X180000Y1440000D03*
Y1500000D03*
X176492Y1447634D03*
X180308D03*
X134935Y1486138D03*
X135095Y1499138D03*
X171595Y1435453D03*
X148095Y1437756D03*
X171895Y1450453D03*
X148095Y1447205D03*
Y1453504D03*
Y1462953D03*
Y1472402D03*
Y1478701D03*
Y1488150D03*
Y1497599D03*
X171595Y1495453D03*
Y1500453D03*
X130000Y1470000D03*
X122000D03*
X114000D03*
X140000Y1464000D03*
X118000Y1470000D03*
X148000Y1458000D03*
X126000Y1466000D03*
X173095Y1461378D03*
X180000Y1451930D03*
X176800D03*
X144595Y1440281D03*
Y1444681D03*
Y1490674D03*
Y1495074D03*
X139095Y1431432D03*
Y1434632D03*
Y1481826D03*
Y1485026D03*
Y1500723D03*
X148095Y1468752D03*
X173100Y1466300D03*
X135095Y1505508D03*
X134995Y1518304D03*
X147700Y1545500D03*
X123400Y1522600D03*
X116500Y1505500D03*
X180000Y1520000D03*
X130600Y1549100D03*
X134995Y1524138D03*
X148095Y1507047D03*
Y1516496D03*
Y1525945D03*
Y1535394D03*
X173000Y1529000D03*
X123500Y1505200D03*
X144200Y1545500D03*
X114000Y1573200D03*
X128250Y1506500D03*
X144595Y1509572D03*
Y1513972D03*
Y1528470D03*
Y1532870D03*
X139095Y1503923D03*
Y1519621D03*
Y1522821D03*
X171595Y1525453D03*
X143500Y1625500D03*
X119534Y1621975D03*
X113841Y1580900D03*
X153700Y1633600D03*
X181500Y1641500D03*
X182500Y1622500D03*
X172000Y1595000D03*
X171500Y1613500D03*
X143300Y1586900D03*
X146800D03*
X138800Y1585100D03*
X135300D03*
X126800Y1630100D03*
X130300D03*
X133800D03*
X126800Y1626600D03*
X130300D03*
X137300Y1630100D03*
Y1626600D03*
X133800D03*
X114000Y1576700D03*
X150200Y1628000D03*
X160200Y1710300D03*
X117300Y1696500D03*
X136600Y1681900D03*
X121700Y1654800D03*
X143000Y1656000D03*
X137000Y1666500D03*
X120000Y1678000D03*
X123000Y1702000D03*
X136700Y1720100D03*
X160000Y1720000D03*
Y1700000D03*
X180000D03*
Y1680000D03*
X113200Y1659800D03*
Y1656300D03*
X117000Y1654600D03*
X126900Y1654700D03*
X144400Y1720400D03*
X159800Y1730000D03*
X148000Y1787000D03*
X125000Y1757834D03*
Y1746034D03*
X177717Y1778162D03*
X180075Y1790692D03*
X125000Y1750334D03*
Y1753534D03*
X136500Y1733000D03*
X137000Y1727500D03*
X140825Y1729825D03*
X157898Y1780145D03*
X140300Y1724100D03*
X147200Y1724400D03*
X135065Y1835438D03*
X128800Y1854000D03*
X145500Y1807500D03*
X136500Y1811500D03*
X140000Y1820000D03*
X160000Y1800000D03*
X180000D03*
Y1840000D03*
X180308Y1853146D03*
X176492D03*
X135065Y1841650D03*
X171595Y1825965D03*
X148095Y1833819D03*
X171595Y1840965D03*
X148095Y1843268D03*
X171595Y1855965D03*
X148095Y1852717D03*
Y1859016D03*
X173095Y1866890D03*
X148000Y1864000D03*
X180000Y1857442D03*
X176800D03*
X144595Y1850193D03*
Y1845793D03*
X139095Y1840144D03*
Y1836944D03*
X151452Y1810000D03*
X134895Y1905020D03*
X128800Y1921300D03*
X129500Y1883500D03*
X115228Y1879770D03*
X128200Y1900300D03*
X180000Y1880000D03*
Y1900000D03*
Y1940000D03*
X134895Y1886150D03*
Y1891650D03*
Y1910650D03*
X134995Y1923650D03*
Y1929650D03*
X148095Y1868465D03*
Y1877914D03*
Y1884213D03*
Y1893662D03*
Y1903111D03*
Y1912559D03*
Y1922008D03*
Y1931457D03*
X171595Y1900965D03*
Y1905965D03*
X173000Y1934500D03*
X140000Y1870000D03*
X144595Y1900586D03*
Y1896186D03*
Y1919484D03*
Y1915084D03*
Y1938382D03*
Y1933982D03*
X139095Y1890538D03*
Y1887338D03*
Y1909435D03*
Y1906235D03*
Y1928333D03*
Y1925133D03*
X171595Y1930965D03*
X113500Y1875970D03*
X173500Y1871700D03*
X133000Y1977100D03*
X114200Y1974100D03*
X118500Y1971400D03*
X139100Y1977100D03*
X172559Y1986626D03*
X152559D03*
X132559D03*
X148095Y1940906D03*
X123200Y1947250D03*
X130500Y1946200D03*
X137300Y1969900D03*
X136800Y1959900D03*
X150800Y1958900D03*
X150600Y1970300D03*
X196665Y35585D03*
X205625Y38750D03*
X240000Y20000D03*
Y40000D03*
X230018Y5500D03*
X250018D03*
X190018D03*
X210018D03*
X187800Y39000D03*
Y35500D03*
X208150Y32250D03*
X220000Y80000D03*
X240000D03*
X200000D03*
X220500Y67500D03*
X240000Y140000D03*
X220000D03*
Y160000D03*
X240000D03*
X200000Y180000D03*
X220000D03*
X240000D03*
X198800Y158000D03*
Y162500D03*
Y167000D03*
X194500Y236902D03*
X200000Y200000D03*
X240000Y220000D03*
X220000D03*
Y200000D03*
X240000D03*
X200000Y260000D03*
X240000D03*
X220000D03*
X194500Y243300D03*
X190500Y238501D03*
Y241701D03*
X200000Y280000D03*
X220000D03*
X240000D03*
Y320000D03*
Y300000D03*
X220000D03*
X200000D03*
Y320000D03*
X220000D03*
X240000Y340000D03*
X220000Y360000D03*
X240000D03*
X220000Y340000D03*
X200000D03*
Y360000D03*
X220000Y480000D03*
X200000D03*
X220000Y460000D03*
X200000D03*
X220000Y420000D03*
X200000Y440000D03*
Y420000D03*
Y520000D03*
X220000D03*
X195500Y531250D03*
Y546250D03*
Y538750D03*
X188854Y527099D03*
Y530902D03*
X206500Y538750D03*
Y546250D03*
Y531250D03*
X220000Y620000D03*
X240000Y600000D03*
Y580000D03*
X200000D03*
X195250Y561300D03*
Y576700D03*
X200250Y572100D03*
X190500Y639713D03*
X200000Y700000D03*
X220000D03*
Y680000D03*
X200000D03*
Y660000D03*
X220000D03*
Y640000D03*
X190500Y651513D03*
Y644013D03*
Y647213D03*
X240000Y760000D03*
X220000Y720000D03*
Y740000D03*
X200000Y760000D03*
Y740000D03*
Y720000D03*
X214700Y784200D03*
X200000Y900000D03*
X240000Y860000D03*
X220000D03*
Y880000D03*
X240000D03*
X190330Y913530D03*
X194200Y985900D03*
X220000Y940000D03*
X240000D03*
X201125Y957200D03*
X195500Y949750D03*
X198900Y969500D03*
X207350Y968627D03*
X198900Y974000D03*
Y978500D03*
X229500Y946600D03*
X198900Y965477D03*
X208875Y957200D03*
X190600Y1045226D03*
X220000Y1040000D03*
Y1020000D03*
X240000D03*
Y1000000D03*
Y1060000D03*
X220000D03*
X240000Y1040000D03*
X190600Y1057024D03*
X190500Y1049525D03*
Y1052725D03*
X200000Y1080000D03*
Y1100000D03*
Y1140000D03*
Y1120000D03*
X220000Y1140000D03*
Y1120000D03*
X240000D03*
Y1100000D03*
X220000D03*
Y1080000D03*
X240000D03*
X255674Y1099470D03*
X196000Y1070300D03*
X208500Y1190000D03*
X200000Y1200000D03*
X240000D03*
Y1180000D03*
X200000Y1160000D03*
Y1280000D03*
X220000D03*
X240000D03*
Y1220000D03*
X220000D03*
X200000Y1340000D03*
X220000D03*
X240000D03*
X200000Y1300000D03*
X220000D03*
X240000D03*
X227000Y1359500D03*
X215000Y1368000D03*
X240000Y1367500D03*
Y1420000D03*
Y1400000D03*
X193400Y1373000D03*
Y1377500D03*
Y1382000D03*
X190400Y1462536D03*
X240000Y1460000D03*
Y1440000D03*
X200000D03*
Y1460000D03*
Y1480000D03*
X240000D03*
Y1500000D03*
X200000D03*
X190400Y1450738D03*
X214500Y1459000D03*
X190500Y1455037D03*
Y1458237D03*
X202000Y1534000D03*
X200000Y1520000D03*
X220000D03*
X240000D03*
X200000Y1560000D03*
X220000D03*
X240000D03*
X203500Y1618500D03*
X229500Y1614500D03*
X189300Y1577200D03*
X220000Y1580000D03*
X248500Y1713005D03*
Y1716808D03*
X242500Y1702500D03*
X251800Y1718400D03*
X220000Y1720000D03*
X200000Y1660000D03*
Y1680000D03*
X220000D03*
Y1660000D03*
X240000Y1680000D03*
Y1660000D03*
X220200Y1740900D03*
X206000Y1735000D03*
X256000Y1745500D03*
X220000Y1734500D03*
X207600Y1777500D03*
X220800Y1763750D03*
X191353Y1772940D03*
X197900Y1781500D03*
X251900Y1769900D03*
X203299Y1763350D03*
X197900Y1786000D03*
Y1790500D03*
X222500Y1776200D03*
X255495Y1738573D03*
X251692D03*
X203299Y1759750D03*
X224875Y1768100D03*
X194620Y1859298D03*
X200000Y1800000D03*
X220000D03*
X240000D03*
X220000Y1840000D03*
X240000D03*
X194620Y1865000D03*
X190500Y1860549D03*
Y1863749D03*
X200000Y1880000D03*
Y1900000D03*
X220000D03*
X240000Y1920000D03*
X220000D03*
X200000D03*
Y1940000D03*
X220000D03*
X240000D03*
X256549Y1898366D03*
X240000Y1880000D03*
X256500D03*
X200000Y1980000D03*
Y1960000D03*
X220000Y1980000D03*
Y1960000D03*
X240000Y1980000D03*
Y1960000D03*
X252559Y1986626D03*
X232559D03*
X212559D03*
X192559D03*
X300000Y40000D03*
Y20000D03*
X320000D03*
Y40000D03*
X260000D03*
Y20000D03*
X280000D03*
Y40000D03*
X310018Y5500D03*
X330018D03*
X270018D03*
X290018D03*
X320000Y80000D03*
X300000Y60000D03*
X320000D03*
Y120000D03*
X300000D03*
X280000D03*
X260000Y100000D03*
X280000D03*
X300000D03*
X320000D03*
X300000Y80000D03*
X280000D03*
X260000D03*
Y160000D03*
X320000D03*
X300000Y140000D03*
X320000D03*
X260000Y180000D03*
X280000D03*
X292600Y166955D03*
X280000Y220000D03*
X260000D03*
Y200000D03*
X280000D03*
X300000D03*
Y220000D03*
X320000D03*
Y240000D03*
Y320000D03*
X300000D03*
X280000D03*
X260000D03*
X320000Y280000D03*
X300000D03*
X260000Y300000D03*
X318656Y391440D03*
X326156D03*
X280000Y360000D03*
X260000D03*
Y340000D03*
X280000D03*
X300000D03*
X320000D03*
X304553Y374081D03*
X313500Y386000D03*
X309000Y365000D03*
X313500Y362000D03*
X320000Y359500D03*
X327500Y373000D03*
X305100Y407700D03*
X293000Y385000D03*
X294500Y408000D03*
X315000Y412000D03*
X321400Y404400D03*
X327500Y377000D03*
X321500Y408500D03*
X312500Y393050D03*
X304400Y416200D03*
X280000Y460000D03*
Y480000D03*
X300000D03*
Y460000D03*
X320000D03*
X300000Y440000D03*
X280000D03*
Y420000D03*
X260000D03*
Y440000D03*
Y480000D03*
Y460000D03*
X321500Y413000D03*
X303200Y422600D03*
X313200Y427500D03*
X317000D03*
X321500Y425200D03*
Y417000D03*
Y421000D03*
X260000Y520000D03*
X320000Y540000D03*
X296470Y555500D03*
X292667D03*
X297300Y505017D03*
X260000Y560000D03*
Y600000D03*
X280000Y620000D03*
X260000D03*
X302500Y583000D03*
X297500D03*
Y588000D03*
X302500D03*
X300000Y585500D03*
X288000Y586484D03*
X313000Y559000D03*
X329600Y583200D03*
X273500Y597000D03*
Y589000D03*
Y585000D03*
Y577000D03*
X284000Y612000D03*
X273500Y573000D03*
Y565000D03*
X296000Y612000D03*
X292000D03*
X316000D03*
X308000D03*
X304000D03*
X290580Y559000D03*
X298450D03*
X320100Y587200D03*
X317500Y559000D03*
X286130Y615700D03*
X270000Y579030D03*
X310030Y615500D03*
X298030Y621000D03*
X269800Y590930D03*
X270000Y567130D03*
X289933Y615700D03*
X270000Y582833D03*
X313833Y615500D03*
X301833Y621000D03*
X269800Y594733D03*
X270000Y570933D03*
X298500Y660200D03*
Y680200D03*
X320000Y700000D03*
X260000D03*
X320000Y640000D03*
X300000D03*
X280000D03*
X260000D03*
X298200Y720000D03*
X260000D03*
X320000D03*
X293500Y738000D03*
X326167Y811099D03*
Y814902D03*
X304400Y846700D03*
X321500Y807000D03*
X297840Y804552D03*
X280000Y820000D03*
X325053Y782652D03*
X309000Y795000D03*
X321500Y843000D03*
X323000Y819500D03*
X313500Y792000D03*
X320000Y789500D03*
X327500Y803000D03*
X304500Y836700D03*
X301300Y822550D03*
X292000Y837000D03*
X321500Y847000D03*
X315000Y842000D03*
X321500Y838500D03*
X321400Y834400D03*
X327500Y807000D03*
X312000Y824500D03*
X260000Y860000D03*
Y880000D03*
X300000D03*
X280000D03*
Y860000D03*
X295200Y903000D03*
X305200D03*
Y913000D03*
X295200D03*
X303500Y853100D03*
X321500Y855200D03*
Y851000D03*
X317000Y857900D03*
X313200D03*
X260000Y940000D03*
X280000D03*
X300000D03*
X260000Y980000D03*
X280000D03*
X300000D03*
X292500Y965500D03*
X320000Y1060000D03*
X300000D03*
X260000D03*
Y1040000D03*
X280000D03*
X300000D03*
X320000D03*
Y1020000D03*
X280000D03*
X300000D03*
X260000D03*
X280000Y1000000D03*
X300000D03*
X320000D03*
Y1140000D03*
X260000Y1120000D03*
X280000D03*
X300000D03*
X320000Y1100000D03*
X300000D03*
Y1080000D03*
X320000D03*
X294000Y1111500D03*
X260000Y1200000D03*
X280000D03*
Y1180000D03*
X260000Y1160000D03*
X296011Y1185470D03*
X309000Y1166500D03*
X295400Y1172655D03*
X313500Y1187500D03*
X320000Y1161000D03*
X327500Y1174500D03*
X305200Y1208300D03*
X321400Y1205900D03*
X321500Y1210000D03*
X327500Y1178500D03*
X312500Y1194000D03*
X304500Y1217500D03*
X320000Y1280000D03*
X300000Y1240000D03*
X320000Y1260000D03*
X300000Y1280000D03*
Y1260000D03*
X280000Y1280000D03*
X260000D03*
Y1260000D03*
X280000D03*
Y1220000D03*
X260000D03*
X321500Y1214500D03*
X295000Y1245000D03*
X294500Y1254000D03*
X302500Y1224000D03*
X321600Y1226600D03*
X313200Y1228800D03*
X317000D03*
X314437Y1213382D03*
X321500Y1222500D03*
Y1218500D03*
X280000Y1340000D03*
X260000D03*
X300000Y1300000D03*
X280000D03*
X260000D03*
X287167Y1380000D03*
X290970D03*
X311500Y1389000D03*
X280000Y1380000D03*
X260000Y1400000D03*
Y1420000D03*
X300000Y1421500D03*
X302500Y1424000D03*
X297500D03*
Y1419000D03*
X302500D03*
X303500Y1389000D03*
X297600Y1392000D03*
X273500Y1407500D03*
X319500Y1389000D03*
X301400Y1401500D03*
X315500Y1389000D03*
X293100Y1383500D03*
X284900D03*
X273500Y1419500D03*
Y1411500D03*
Y1423500D03*
X326500Y1417500D03*
Y1425700D03*
Y1405400D03*
Y1413500D03*
Y1429700D03*
X328000Y1381500D03*
Y1374000D03*
X327500Y1368500D03*
X273500Y1403500D03*
X307500Y1389000D03*
X330000Y1423470D03*
X270100Y1425697D03*
X330300Y1411100D03*
X270000Y1413530D03*
X330000Y1419667D03*
X270100Y1429500D03*
X330300Y1407297D03*
X270000Y1417333D03*
X260000Y1440000D03*
X300984Y1433500D03*
X273500Y1431500D03*
X287600Y1448000D03*
X279650D03*
X299600D03*
X291600D03*
X326500Y1437700D03*
X311600Y1448000D03*
X303600D03*
X330000Y1435170D03*
X293830Y1451500D03*
X305830Y1451300D03*
X282030Y1451400D03*
X330000Y1431367D03*
X297633Y1451500D03*
X309633Y1451300D03*
X285833Y1451400D03*
X260000Y1520000D03*
X280000D03*
X300000D03*
X320000Y1540000D03*
Y1560000D03*
X300000D03*
X280000D03*
X260000D03*
X258585Y1508386D03*
X260000Y1620000D03*
Y1600000D03*
X300000Y1620000D03*
X280000Y1600000D03*
Y1620000D03*
X300000Y1600000D03*
X320000D03*
X318156Y1692440D03*
X325656D03*
X289300Y1696200D03*
Y1701800D03*
X292200Y1688900D03*
X295800D03*
X306200Y1689400D03*
X259000Y1702500D03*
X260000Y1680000D03*
Y1660000D03*
X321500Y1713000D03*
X327500Y1673000D03*
X305300Y1715700D03*
X306200Y1709600D03*
X301800Y1722100D03*
X265500Y1722000D03*
X283500D03*
X285000Y1700600D03*
X295600Y1693400D03*
X285000Y1697400D03*
X292400Y1693400D03*
X315000Y1712000D03*
X321500Y1721000D03*
X327500Y1677000D03*
X321500Y1717000D03*
Y1708500D03*
X321400Y1704400D03*
X313500Y1692500D03*
X320000Y1760000D03*
Y1780000D03*
X260000Y1740000D03*
X288000Y1742500D03*
X293000D03*
X284000Y1731250D03*
X268800Y1774600D03*
X276402Y1726146D03*
X272599D03*
X297000Y1777000D03*
Y1752000D03*
X302000D03*
X321500Y1725200D03*
X317000Y1727300D03*
X313200D03*
X260000Y1800000D03*
Y1840000D03*
X280000D03*
X320000Y1860000D03*
X300000D03*
Y1840000D03*
X320000Y1820000D03*
Y1840000D03*
X271500Y1795000D03*
X279500D03*
X287500D03*
X300000Y1800000D03*
X320000Y1940000D03*
X300000D03*
X280000D03*
X260000D03*
X280071Y1924667D03*
X300000Y1900000D03*
Y1920000D03*
X320000D03*
Y1900000D03*
X300000Y1880000D03*
X320000D03*
X260000Y1980000D03*
Y1960000D03*
X280000Y1980000D03*
Y1960000D03*
X300000Y1980000D03*
Y1960000D03*
X320000Y1980000D03*
Y1960000D03*
X312559Y1986626D03*
X292559D03*
X272559D03*
X380000Y20000D03*
Y40000D03*
X400000D03*
Y20000D03*
X340000Y40000D03*
Y20000D03*
X360000Y40000D03*
Y20000D03*
X390018Y5500D03*
X350018D03*
X370018D03*
X400000Y100000D03*
Y80000D03*
X377500Y98000D03*
X400000Y60000D03*
X340000Y80000D03*
Y100000D03*
Y60000D03*
X400000Y120000D03*
X340000D03*
X373500Y98000D03*
X363750Y65250D03*
X352500Y68500D03*
X358500Y93500D03*
X374300Y81400D03*
X363750Y73300D03*
X378100Y81500D03*
X363750Y54250D03*
X382200Y81500D03*
X382000Y98000D03*
X358000Y64000D03*
X344500Y71750D03*
X340000Y180000D03*
X360000D03*
X380000D03*
X400000D03*
Y140000D03*
Y160000D03*
X380000Y140000D03*
Y160000D03*
X360000Y140000D03*
Y160000D03*
X340000D03*
Y140000D03*
X357250Y124000D03*
X360750D03*
X400000Y220000D03*
Y200000D03*
X380000D03*
X340000Y240000D03*
Y260000D03*
X360000D03*
Y280000D03*
X369000Y294000D03*
X370000Y411000D03*
Y405500D03*
X375500D03*
X381000D03*
X375500Y411000D03*
X381000D03*
X359000D03*
X364500D03*
Y405500D03*
X359000D03*
X370000Y400000D03*
X381000D03*
X375500D03*
X370000Y389000D03*
Y394500D03*
X375500D03*
Y389000D03*
X381000D03*
Y394500D03*
X364500Y400000D03*
X365000Y394500D03*
Y389000D03*
X359000D03*
Y394500D03*
Y400000D03*
X370128Y361337D03*
X349706Y355693D03*
X356250Y349000D03*
X337500Y406250D03*
X331500Y393000D03*
X368500Y364500D03*
X372000D03*
X401500Y401500D03*
X397000Y383750D03*
X383750Y349000D03*
X391800Y355800D03*
X401500Y410250D03*
X356257Y344176D03*
X391750Y344500D03*
X383750D03*
X348256Y344114D03*
X331500Y389000D03*
X365100Y371200D03*
X397000Y380250D03*
X375200Y371250D03*
X349870Y348870D03*
X331300Y408500D03*
X400000Y440000D03*
Y460000D03*
Y480000D03*
X339500Y416750D03*
X370397Y439122D03*
X368500Y436000D03*
X372000D03*
X397000Y414750D03*
X379250Y451000D03*
X385896Y444265D03*
X343750Y451000D03*
X350241Y444377D03*
X351729Y455810D03*
X379258Y455892D03*
X387249Y455882D03*
X343729Y455810D03*
X364758Y429249D03*
X375200Y429250D03*
X350137Y451250D03*
X385607Y451232D03*
X400000Y540000D03*
X340000D03*
X380000Y500000D03*
Y540000D03*
X400000Y520000D03*
X339500Y572667D03*
Y576470D03*
X400000Y560000D03*
X332500Y597000D03*
Y589000D03*
X360000Y580000D03*
X340000Y560000D03*
Y600000D03*
Y620000D03*
X380000D03*
X400000D03*
X380000Y560000D03*
X332500Y605000D03*
X336000Y570580D03*
Y578600D03*
X332500Y593000D03*
Y601000D03*
X380000Y660000D03*
X400000Y640000D03*
Y680000D03*
Y700000D03*
X340000Y660000D03*
Y680000D03*
Y700000D03*
X360000D03*
Y680000D03*
Y660000D03*
Y640000D03*
X380000D03*
X400000Y740000D03*
Y720000D03*
X340000Y740000D03*
Y720000D03*
X360000D03*
X377250Y774500D03*
X385238Y774122D03*
X400000Y780000D03*
X340000D03*
X370000Y841000D03*
Y835500D03*
X375500D03*
X381000D03*
X375500Y841000D03*
X381000D03*
X359000D03*
X364500D03*
Y835500D03*
X359000D03*
X370000Y830000D03*
X381000D03*
X375500D03*
X370000Y819000D03*
Y824500D03*
X375500D03*
Y819000D03*
X381000D03*
Y824500D03*
X364500Y830000D03*
X365000Y824500D03*
Y819000D03*
X359000D03*
Y824500D03*
Y830000D03*
X362000Y797000D03*
X365500D03*
X358000Y794000D03*
X397000Y844750D03*
X339500Y846750D03*
X337500Y836250D03*
X331500Y823000D03*
X401500Y836000D03*
X377250Y779000D03*
X385250Y785700D03*
X395000Y806500D03*
X331500Y819000D03*
X358800Y803600D03*
X368700Y803750D03*
X388250Y803300D03*
X385196Y779112D03*
X331300Y838500D03*
X402000Y844000D03*
X360100Y808080D03*
X371059Y903347D03*
X355622Y919857D03*
X380000Y920000D03*
X400000D03*
Y900000D03*
X368500Y865000D03*
X372000D03*
X379228Y874277D03*
X387250Y881000D03*
X351740Y880717D03*
X343749Y874298D03*
X351792Y885835D03*
X379270Y885897D03*
X387292D03*
X343770D03*
X360800Y858500D03*
X375200Y858250D03*
X343894Y880707D03*
X379372Y880728D03*
X335823Y940330D03*
X340000Y980000D03*
X360000D03*
X380000D03*
X400000D03*
Y960000D03*
X380000D03*
X340000D03*
X360000D03*
Y940000D03*
X380000D03*
X400000D03*
Y1060000D03*
X380000D03*
X400000Y1040000D03*
X380000D03*
X360000Y1060000D03*
X340000D03*
X360000Y1040000D03*
X340000D03*
Y1000000D03*
Y1020000D03*
X360000Y1000000D03*
Y1020000D03*
X380000Y1000000D03*
Y1020000D03*
X400000Y1000000D03*
Y1020000D03*
X360000Y1140000D03*
X340000D03*
X380000Y1100000D03*
X400000Y1080000D03*
X380000D03*
X360000Y1100000D03*
X340000D03*
X360000Y1080000D03*
X340000D03*
Y1160000D03*
X354228Y1164233D03*
X370000Y1212500D03*
Y1207000D03*
X375500D03*
X381000D03*
X375500Y1212500D03*
X381000D03*
X359000D03*
X364500D03*
Y1207000D03*
X359000D03*
X370000Y1201500D03*
X381000D03*
X375500D03*
X370000Y1190500D03*
Y1196000D03*
X375500D03*
Y1190500D03*
X381000D03*
Y1196000D03*
X364500Y1201500D03*
X365000Y1196000D03*
Y1190500D03*
X359000D03*
Y1196000D03*
Y1201500D03*
X337500Y1207750D03*
X331500Y1194500D03*
X371000Y1168000D03*
X367500D03*
X363500Y1165000D03*
X402000Y1202500D03*
X383750Y1150500D03*
X391765Y1157852D03*
X396750Y1181250D03*
X391758Y1145676D03*
X383757Y1145655D03*
X331500Y1190500D03*
X364300Y1174900D03*
X374200Y1174750D03*
X391900Y1150250D03*
X331300Y1210000D03*
X398750Y1188250D03*
X359175Y1179640D03*
X400000Y1280000D03*
Y1260000D03*
X339500Y1218250D03*
X370200Y1239700D03*
X368500Y1236500D03*
X372000D03*
X343749Y1245719D03*
X351771Y1252213D03*
X379249Y1245782D03*
X387208Y1252212D03*
X391500Y1218500D03*
X351750Y1257380D03*
X379270D03*
X387292Y1257360D03*
X343760Y1257381D03*
X365200Y1229800D03*
X400700Y1237500D03*
X375200Y1229750D03*
X343822Y1252222D03*
X379395Y1252274D03*
X400000Y1340000D03*
X380000D03*
Y1320000D03*
X400000D03*
X380000Y1300000D03*
X400000D03*
X360000Y1340000D03*
Y1320000D03*
X340000Y1340000D03*
X380000Y1420000D03*
Y1400000D03*
X400000Y1420000D03*
Y1400000D03*
Y1380000D03*
Y1360000D03*
X380000D03*
Y1380000D03*
X360000D03*
Y1360000D03*
X340000D03*
Y1380000D03*
X380000Y1500000D03*
X360000D03*
X340000Y1480000D03*
Y1460000D03*
X400000D03*
X380000Y1440000D03*
X400000D03*
X360000Y1560000D03*
X400000Y1540000D03*
X380000D03*
X360000D03*
Y1520000D03*
X380000D03*
X400000D03*
Y1580000D03*
X380000D03*
X348250Y1649000D03*
X356247Y1644123D03*
X348257Y1644132D03*
X356174Y1649291D03*
X334500Y1650000D03*
Y1665000D03*
X380000Y1660000D03*
X400000D03*
X359000Y1705500D03*
Y1700000D03*
Y1694500D03*
Y1689000D03*
X365000D03*
Y1694500D03*
X364500Y1700000D03*
Y1705500D03*
Y1711000D03*
X359000D03*
X381000D03*
X375500D03*
X381000Y1705500D03*
X375500D03*
X381000Y1694500D03*
Y1689000D03*
X375500D03*
Y1694500D03*
X370000D03*
Y1689000D03*
Y1705500D03*
Y1711000D03*
X381000Y1700000D03*
X375500D03*
X370000D03*
X402000Y1701000D03*
X339500Y1716750D03*
X337500Y1706250D03*
X331500Y1695000D03*
X368500Y1664000D03*
X372500Y1667000D03*
X376000D03*
X388750Y1673000D03*
X356238Y1655722D03*
X331500Y1691000D03*
X369100Y1673700D03*
X385250Y1673000D03*
X331500Y1708500D03*
X395500Y1690500D03*
X376890Y1678000D03*
X368500Y1768000D03*
X400000Y1760000D03*
X365400Y1734400D03*
X369000Y1734500D03*
X372500D03*
X393000Y1723500D03*
X351750Y1751000D03*
X343709Y1744187D03*
X376808Y1755434D03*
X373005D03*
X379000Y1736000D03*
X351750Y1755500D03*
X343750D03*
X383000Y1736300D03*
X365700Y1727700D03*
X383000Y1728700D03*
X375700Y1727750D03*
X343668Y1750741D03*
X379000Y1726000D03*
X400000Y1860000D03*
X380000D03*
X360000D03*
X340000D03*
Y1800000D03*
Y1840000D03*
X360000D03*
X380000D03*
X400000D03*
Y1820000D03*
X380000D03*
X360000D03*
X340000D03*
X360000Y1800000D03*
X400000D03*
X380000D03*
X400000Y1940000D03*
X380000D03*
X360000D03*
X340000D03*
Y1900000D03*
Y1920000D03*
X360000D03*
Y1900000D03*
X380000D03*
Y1920000D03*
X400000D03*
Y1900000D03*
X340000Y1880000D03*
X360000D03*
X380000D03*
X400000D03*
X340000Y1980000D03*
Y1960000D03*
X360000Y1980000D03*
Y1960000D03*
X380000Y1980000D03*
Y1960000D03*
X400000Y1980000D03*
Y1960000D03*
X392559Y1986626D03*
X372559D03*
X352559D03*
X332559D03*
X460000Y20000D03*
Y40000D03*
X420000Y20000D03*
Y40000D03*
X440000D03*
Y20000D03*
X470018Y5500D03*
X410018D03*
X430018D03*
X450018D03*
X460000Y100000D03*
X420000D03*
X440000D03*
X460000Y80000D03*
Y60000D03*
X440000D03*
Y80000D03*
X420000D03*
Y60000D03*
X460000Y120000D03*
X440000D03*
X420000D03*
Y180000D03*
X440000D03*
X460000D03*
Y140000D03*
Y160000D03*
X440000D03*
Y140000D03*
X420000D03*
Y160000D03*
Y200000D03*
X460000D03*
X440000D03*
X420000Y220000D03*
X440000D03*
X460000D03*
Y240000D03*
X440000D03*
X420000D03*
Y260000D03*
X440000D03*
X460000D03*
X440000Y280000D03*
X460000D03*
X440000Y320000D03*
X460000D03*
Y300000D03*
X405500Y277500D03*
X405000Y289000D03*
X440000Y400000D03*
X460000D03*
Y380000D03*
X440000D03*
Y360000D03*
X460000D03*
Y340000D03*
X440000D03*
X460000Y480000D03*
Y460000D03*
X440000Y480000D03*
Y460000D03*
Y440000D03*
X460000D03*
Y420000D03*
X440000D03*
X410550Y420500D03*
X420000Y520000D03*
Y540000D03*
X440000D03*
Y520000D03*
X460000D03*
Y500000D03*
X420000D03*
Y620000D03*
X440000Y600000D03*
X460000Y580000D03*
X420000Y600000D03*
X440000Y580000D03*
X420000Y560000D03*
Y700000D03*
X460000Y660000D03*
Y680000D03*
Y700000D03*
X420000Y680000D03*
Y660000D03*
Y720000D03*
Y740000D03*
X460000Y720000D03*
Y760000D03*
X420000D03*
Y840000D03*
X440000D03*
X460000D03*
Y820000D03*
Y800000D03*
Y780000D03*
X420000D03*
X414281Y820751D03*
X421000Y812750D03*
X425890Y820729D03*
X425891Y812750D03*
X404000Y840500D03*
X420722Y820627D03*
X420000Y920000D03*
X440000D03*
X460000D03*
Y900000D03*
X440000D03*
X420000D03*
Y880000D03*
X460000D03*
X440000D03*
X420000Y860000D03*
X440000D03*
X460000D03*
X410550Y850500D03*
X420000Y980000D03*
X440000D03*
X460000D03*
Y960000D03*
X440000D03*
X420000D03*
Y940000D03*
X440000D03*
X460000D03*
X420000Y1060000D03*
X440000Y1040000D03*
X420000D03*
Y1000000D03*
Y1020000D03*
X440000Y1000000D03*
Y1020000D03*
X460000D03*
Y1000000D03*
X440000Y1120000D03*
X460000D03*
Y1080000D03*
X420000Y1200000D03*
X440000D03*
X460000D03*
Y1160000D03*
Y1180000D03*
X440000Y1160000D03*
Y1180000D03*
X420000Y1160000D03*
Y1180000D03*
X405500Y1192000D03*
X420000Y1280000D03*
Y1240000D03*
X440000D03*
X460000D03*
Y1260000D03*
X440000D03*
X420000D03*
X460000Y1280000D03*
X440000D03*
X420743Y1215266D03*
X414274Y1223246D03*
X408300Y1237500D03*
X425500Y1215250D03*
Y1223250D03*
X420763Y1223185D03*
X420000Y1340000D03*
Y1320000D03*
X440000D03*
Y1340000D03*
X460000D03*
Y1320000D03*
X440000Y1300000D03*
X420000D03*
X460000D03*
X440000Y1420000D03*
X420000D03*
Y1400000D03*
Y1380000D03*
Y1360000D03*
X440000Y1400000D03*
Y1360000D03*
Y1380000D03*
X460000D03*
Y1360000D03*
Y1420000D03*
Y1400000D03*
X440000Y1500000D03*
X420000Y1480000D03*
X440000D03*
Y1460000D03*
X420000D03*
Y1440000D03*
X440000D03*
X460000Y1500000D03*
Y1480000D03*
Y1460000D03*
Y1440000D03*
X420000Y1540000D03*
X460000Y1520000D03*
Y1580000D03*
X440000D03*
X420000D03*
Y1700000D03*
Y1680000D03*
Y1660000D03*
X440000Y1680000D03*
X460000D03*
Y1660000D03*
X421000Y1713750D03*
X414299Y1721750D03*
X425879Y1721724D03*
X425500Y1713750D03*
X420732Y1721757D03*
X420000Y1760000D03*
X406500Y1736500D03*
X440000Y1780000D03*
Y1760000D03*
X460000D03*
Y1780000D03*
X450000Y1803500D03*
X440000Y1860000D03*
X420000D03*
Y1840000D03*
X440000D03*
X420000Y1820000D03*
X460000Y1840000D03*
Y1860000D03*
Y1940000D03*
X440000D03*
X420000D03*
Y1900000D03*
Y1920000D03*
X440000D03*
Y1900000D03*
X460000Y1920000D03*
Y1900000D03*
X420000Y1880000D03*
X440000D03*
X460000D03*
X420000Y1980000D03*
Y1960000D03*
X440000Y1980000D03*
Y1960000D03*
X460000Y1980000D03*
Y1960000D03*
X472559Y1986626D03*
X452559D03*
X432559D03*
X412559D03*
X500000Y40000D03*
X480000D03*
X520000D03*
X530018Y5500D03*
X510018D03*
X490018D03*
X500000Y20000D03*
X480000D03*
X520000D03*
X540000Y40000D03*
Y20000D03*
Y100000D03*
X520000D03*
X500000D03*
X480000D03*
Y120000D03*
X500000D03*
X520000D03*
X480000Y60000D03*
Y80000D03*
X500000D03*
Y60000D03*
X520000D03*
Y80000D03*
X540000Y120000D03*
Y80000D03*
Y60000D03*
X480000Y140000D03*
Y160000D03*
X500000D03*
Y140000D03*
X520000D03*
Y160000D03*
Y180000D03*
X500000D03*
X480000D03*
X540000Y160000D03*
Y140000D03*
Y180000D03*
X520000Y260000D03*
X500000D03*
X520000Y240000D03*
X480000D03*
X500000D03*
Y220000D03*
X480000D03*
Y200000D03*
X500000D03*
X520000D03*
Y220000D03*
X540000Y260000D03*
Y220000D03*
Y240000D03*
Y200000D03*
X500000Y280000D03*
X520000D03*
X480000D03*
Y300000D03*
X500000D03*
X520000D03*
Y320000D03*
X500000D03*
X480000D03*
X540000Y280000D03*
Y300000D03*
Y320000D03*
X500000Y400000D03*
X520000D03*
Y380000D03*
X540000Y400000D03*
Y380000D03*
Y360000D03*
Y340000D03*
X480000Y400000D03*
Y340000D03*
X500000D03*
X520000D03*
Y360000D03*
X500000D03*
X480000D03*
Y380000D03*
Y440000D03*
X500000D03*
X480000Y420000D03*
X500000D03*
X520000D03*
X540000D03*
X520000Y480000D03*
X500000D03*
X480000D03*
Y460000D03*
X500000D03*
X520000D03*
Y440000D03*
X540000Y460000D03*
Y440000D03*
X500000Y500000D03*
X480000D03*
X520000Y520000D03*
X500000Y540000D03*
X540000D03*
X520000Y560000D03*
X540000D03*
Y580000D03*
X500000D03*
Y600000D03*
X520000D03*
X540000D03*
X520000Y580000D03*
X480000Y560000D03*
X540000Y700000D03*
X520000D03*
X500000D03*
X480000D03*
X540000Y680000D03*
X520000D03*
X500000D03*
X480000D03*
X540000Y660000D03*
X520000D03*
X500000D03*
X480000D03*
Y640000D03*
X500000D03*
X520000D03*
X540000D03*
X520000Y720000D03*
X500000D03*
X480000D03*
X540000Y740000D03*
X480000Y760000D03*
X500000D03*
X520000D03*
X540000D03*
X520000Y780000D03*
X500000D03*
X480000D03*
Y800000D03*
X500000D03*
X520000D03*
X480000Y820000D03*
X500000D03*
X520000D03*
X480000Y840000D03*
X500000D03*
X520000D03*
X540000D03*
Y780000D03*
Y800000D03*
Y820000D03*
X520000Y900000D03*
Y920000D03*
X500000D03*
X480000D03*
X520000Y860000D03*
X500000D03*
X480000D03*
Y880000D03*
X500000D03*
X520000D03*
X480000Y900000D03*
X500000D03*
X540000Y920000D03*
Y860000D03*
Y880000D03*
Y900000D03*
X520000Y980000D03*
X500000D03*
X480000D03*
X520000Y940000D03*
X500000D03*
X480000D03*
Y960000D03*
X500000D03*
X520000D03*
X540000Y980000D03*
Y940000D03*
Y960000D03*
X520000Y1060000D03*
X500000D03*
X480000D03*
Y1000000D03*
X500000Y1040000D03*
X520000D03*
X540000Y1060000D03*
Y1040000D03*
X480000Y1080000D03*
X500000D03*
X520000D03*
Y1120000D03*
X500000D03*
X480000D03*
X540000D03*
Y1100000D03*
X520000Y1200000D03*
X500000D03*
X480000D03*
Y1180000D03*
Y1160000D03*
X500000Y1180000D03*
Y1160000D03*
X520000Y1180000D03*
Y1160000D03*
X540000Y1180000D03*
Y1160000D03*
Y1200000D03*
X480000Y1280000D03*
X500000D03*
X520000D03*
X480000Y1260000D03*
X500000D03*
X520000D03*
X500000Y1240000D03*
X480000D03*
X540000Y1280000D03*
Y1220000D03*
X500000Y1340000D03*
X520000D03*
X480000D03*
Y1320000D03*
X500000D03*
X520000D03*
X480000Y1300000D03*
X500000D03*
X520000D03*
X540000Y1340000D03*
Y1320000D03*
Y1300000D03*
X520000Y1420000D03*
X500000D03*
X480000D03*
X520000Y1380000D03*
Y1400000D03*
X500000Y1380000D03*
Y1400000D03*
X480000Y1380000D03*
Y1400000D03*
X500000Y1360000D03*
X520000D03*
X480000D03*
X540000Y1420000D03*
Y1380000D03*
Y1400000D03*
Y1360000D03*
X520000Y1500000D03*
X500000D03*
X480000D03*
X520000Y1440000D03*
Y1460000D03*
Y1480000D03*
X500000Y1440000D03*
Y1460000D03*
Y1480000D03*
X480000Y1440000D03*
Y1460000D03*
Y1480000D03*
X540000Y1500000D03*
Y1440000D03*
Y1460000D03*
Y1480000D03*
X500000Y1560000D03*
X480000Y1520000D03*
X500000D03*
X520000D03*
X540000D03*
X547659Y1560537D03*
X542159D03*
Y1566037D03*
X547659D03*
X480000Y1580000D03*
X540000Y1680000D03*
X520000D03*
X500000D03*
X480000D03*
Y1700000D03*
Y1660000D03*
Y1720000D03*
X500000D03*
X520000D03*
Y1700000D03*
X500000D03*
X520000Y1660000D03*
X500000D03*
X540000Y1700000D03*
Y1720000D03*
Y1660000D03*
Y1780000D03*
X520000Y1760000D03*
X480000Y1780000D03*
X500000D03*
X520000D03*
X480000Y1760000D03*
X500000D03*
X520000Y1740000D03*
X500000D03*
X480000D03*
X540000Y1760000D03*
Y1740000D03*
Y1820000D03*
Y1840000D03*
Y1860000D03*
X520000D03*
X480000D03*
X500000Y1840000D03*
X520000D03*
X500000Y1820000D03*
X480000D03*
X520000D03*
X540000Y1940000D03*
X500000D03*
X520000D03*
X480000D03*
X520000Y1920000D03*
X500000D03*
X480000D03*
X520000Y1900000D03*
X500000D03*
X480000D03*
Y1880000D03*
X500000D03*
X520000D03*
X540000Y1900000D03*
Y1880000D03*
Y1920000D03*
X492559Y1986626D03*
X512559D03*
X532559D03*
X520000Y1960000D03*
Y1980000D03*
X500000Y1960000D03*
Y1980000D03*
X480000Y1960000D03*
Y1980000D03*
X540000Y1960000D03*
Y1980000D03*
X580000Y40000D03*
X560000D03*
X600000D03*
X590018Y5500D03*
X570018D03*
X550018D03*
X580000Y20000D03*
X560000D03*
X600000D03*
X620000Y40000D03*
X610018Y5500D03*
X620000Y20000D03*
Y100000D03*
X600000D03*
X580000D03*
X560000D03*
Y120000D03*
X580000D03*
X600000D03*
X560000Y60000D03*
Y80000D03*
X580000D03*
Y60000D03*
X600000D03*
Y80000D03*
X620000Y120000D03*
Y80000D03*
Y60000D03*
X560000Y140000D03*
Y160000D03*
X580000D03*
Y140000D03*
X600000D03*
Y160000D03*
Y180000D03*
X580000D03*
X560000D03*
X620000Y160000D03*
Y140000D03*
Y180000D03*
X580000Y260000D03*
X600000D03*
X620000D03*
X560000D03*
X600000Y200000D03*
Y220000D03*
X580000D03*
Y200000D03*
X560000D03*
Y220000D03*
Y240000D03*
X580000D03*
X600000D03*
X620000D03*
Y220000D03*
Y200000D03*
X560000Y320000D03*
X580000D03*
X600000D03*
X620000D03*
X560000Y300000D03*
X580000D03*
X600000D03*
X620000D03*
X580000Y280000D03*
X600000D03*
X620000D03*
X560000D03*
X620000Y400000D03*
X600000D03*
X580000D03*
X560000D03*
Y380000D03*
X580000D03*
X600000D03*
X620000D03*
X560000Y360000D03*
X580000D03*
X600000D03*
X620000D03*
X560000Y340000D03*
X580000D03*
X600000D03*
X620000D03*
X600000Y480000D03*
X620000D03*
Y460000D03*
X580000Y440000D03*
X560000D03*
X620000Y420000D03*
X600000D03*
X580000D03*
X560000D03*
Y460000D03*
X620000Y520000D03*
X600000D03*
X580000D03*
Y500000D03*
X600000Y540000D03*
Y500000D03*
X620000D03*
X580000Y540000D03*
X560000D03*
X620000D03*
Y560000D03*
X580000D03*
X600000D03*
X560000D03*
Y580000D03*
X600000D03*
X620000Y600000D03*
X600000D03*
X580000D03*
Y580000D03*
X620000D03*
Y640000D03*
X600000D03*
X580000D03*
X560000D03*
X620000Y700000D03*
X600000D03*
X580000D03*
X560000D03*
X620000Y680000D03*
X600000D03*
X580000D03*
X560000D03*
X620000Y660000D03*
X600000D03*
X580000D03*
X560000D03*
Y740000D03*
X580000D03*
X600000D03*
X620000D03*
X580000Y760000D03*
X600000D03*
X620000D03*
X560000D03*
X580000Y780000D03*
X600000D03*
X620000D03*
X580000Y800000D03*
X600000D03*
X620000D03*
X580000Y820000D03*
X600000D03*
X620000D03*
X560000Y840000D03*
X580000D03*
X600000D03*
X560000Y780000D03*
Y800000D03*
X620000Y840000D03*
X600000Y920000D03*
X580000D03*
X560000D03*
X600000Y860000D03*
X580000D03*
X560000D03*
Y900000D03*
Y880000D03*
X580000D03*
Y900000D03*
X600000D03*
Y880000D03*
X620000Y920000D03*
Y880000D03*
Y900000D03*
Y860000D03*
X600000Y980000D03*
X580000D03*
X560000D03*
X580000Y940000D03*
X560000D03*
Y960000D03*
X580000D03*
X600000D03*
Y940000D03*
X620000D03*
Y960000D03*
Y980000D03*
X600000Y1060000D03*
X580000D03*
X560000D03*
Y1040000D03*
X580000D03*
X600000D03*
X620000D03*
Y1060000D03*
X560000Y1100000D03*
X580000D03*
X600000D03*
Y1120000D03*
X580000D03*
X560000D03*
X620000D03*
Y1100000D03*
X560000Y1180000D03*
X580000D03*
Y1160000D03*
X600000Y1180000D03*
Y1160000D03*
Y1200000D03*
X580000D03*
X560000D03*
X620000D03*
Y1160000D03*
Y1180000D03*
X580000Y1260000D03*
Y1240000D03*
X560000D03*
X600000Y1220000D03*
X580000D03*
X560000D03*
X600000Y1260000D03*
Y1240000D03*
X620000Y1280000D03*
Y1220000D03*
Y1240000D03*
Y1260000D03*
X560000Y1340000D03*
X580000D03*
X600000D03*
X560000Y1320000D03*
X580000D03*
X560000Y1300000D03*
X620000D03*
X600000Y1420000D03*
X580000D03*
X560000D03*
X600000Y1400000D03*
X580000Y1380000D03*
Y1400000D03*
X560000Y1380000D03*
Y1400000D03*
X580000Y1360000D03*
X600000D03*
X620000Y1420000D03*
Y1400000D03*
Y1380000D03*
Y1360000D03*
X600000Y1500000D03*
X580000D03*
X560000D03*
X600000Y1440000D03*
Y1460000D03*
Y1480000D03*
X580000Y1440000D03*
Y1460000D03*
Y1480000D03*
X560000Y1440000D03*
Y1460000D03*
Y1480000D03*
X620000Y1500000D03*
Y1480000D03*
Y1460000D03*
Y1440000D03*
X560000Y1520000D03*
X580000D03*
X620000Y1680000D03*
X560000D03*
X580000D03*
X600000D03*
Y1700000D03*
Y1720000D03*
X580000D03*
Y1700000D03*
X560000D03*
Y1720000D03*
X600000Y1660000D03*
X580000D03*
X560000D03*
X620000Y1700000D03*
Y1720000D03*
Y1660000D03*
Y1780000D03*
X600000D03*
X580000D03*
X560000D03*
X620000Y1760000D03*
X600000D03*
X580000D03*
X560000D03*
X620000Y1740000D03*
X600000D03*
X580000D03*
X560000D03*
Y1840000D03*
Y1860000D03*
X620000Y1800000D03*
X600000D03*
X580000D03*
X560000D03*
X620000Y1840000D03*
X600000D03*
X580000D03*
X620000Y1860000D03*
X600000D03*
X580000D03*
X560000Y1940000D03*
X580000D03*
X600000D03*
X620000D03*
X560000Y1880000D03*
X620000D03*
X600000D03*
X580000D03*
X620000Y1900000D03*
X600000D03*
X580000D03*
X620000Y1920000D03*
X600000D03*
X580000D03*
X560000D03*
Y1900000D03*
X620000Y1960000D03*
X600000D03*
X580000D03*
X552559Y1986626D03*
X572559D03*
X592559D03*
X600000Y1980000D03*
X580000D03*
X560000D03*
Y1960000D03*
X612559Y1986626D03*
X620000Y1980000D03*
X660000Y40000D03*
X640000D03*
X670018Y5500D03*
X650018D03*
X630018D03*
X660000Y20000D03*
X640000D03*
X680000D03*
Y40000D03*
X690018Y5500D03*
X680000Y100000D03*
X660000D03*
X640000D03*
Y120000D03*
X660000D03*
X640000Y60000D03*
Y80000D03*
X660000D03*
Y60000D03*
X680000Y120000D03*
Y60000D03*
Y80000D03*
X640000Y140000D03*
Y160000D03*
X660000D03*
Y140000D03*
Y180000D03*
X640000D03*
X680000Y140000D03*
Y160000D03*
Y180000D03*
X660000Y260000D03*
X640000D03*
Y240000D03*
X660000D03*
Y220000D03*
Y200000D03*
X640000Y220000D03*
Y200000D03*
X680000Y260000D03*
Y240000D03*
Y220000D03*
Y200000D03*
X640000Y320000D03*
X660000D03*
X680000D03*
X640000Y300000D03*
X660000D03*
X680000D03*
X640000Y280000D03*
X660000D03*
X680000D03*
X640000Y400000D03*
Y380000D03*
X660000D03*
X640000Y360000D03*
X660000D03*
X680000D03*
X640000Y340000D03*
X660000D03*
X680000D03*
Y480000D03*
Y460000D03*
Y440000D03*
X640000Y480000D03*
X660000D03*
Y460000D03*
X640000D03*
X660000Y440000D03*
X640000D03*
X680000Y420000D03*
X660000Y520000D03*
X640000D03*
X680000D03*
Y500000D03*
X640000D03*
X660000D03*
X640000Y540000D03*
X660000D03*
X680000D03*
X663000Y535500D03*
X680000Y560000D03*
X660000D03*
X640000D03*
X680000Y600000D03*
X660000D03*
X640000D03*
Y580000D03*
X660000D03*
X680000D03*
Y660000D03*
Y680000D03*
X640000Y640000D03*
Y700000D03*
X660000Y680000D03*
X640000D03*
X660000Y660000D03*
X640000D03*
X660000Y640000D03*
X680000D03*
X661500Y650500D03*
X640000Y720000D03*
X660000D03*
X680000D03*
X640000Y740000D03*
X660000D03*
X680000D03*
X640000Y760000D03*
X660000D03*
X680000D03*
X640000Y780000D03*
X660000D03*
X680000D03*
X640000Y800000D03*
X660000D03*
X680000D03*
X640000Y820000D03*
X660000D03*
X680000D03*
X640000Y840000D03*
X660000D03*
X680000D03*
X662000Y826600D03*
X640000Y920000D03*
X660000D03*
X640000Y900000D03*
X660000D03*
X640000Y880000D03*
X660000D03*
X640000Y860000D03*
X660000D03*
X680000Y920000D03*
Y900000D03*
Y880000D03*
Y860000D03*
X640000Y940000D03*
Y960000D03*
X660000D03*
Y980000D03*
X640000D03*
X680000D03*
Y960000D03*
X665000Y937000D03*
X660000Y1040000D03*
X640000D03*
Y1060000D03*
X680000Y1040000D03*
X660000Y1053500D03*
X640000Y1100000D03*
Y1120000D03*
X660000D03*
Y1100000D03*
X680000D03*
Y1120000D03*
Y1080000D03*
X640000Y1200000D03*
X660000D03*
Y1160000D03*
X640000D03*
Y1180000D03*
X680000Y1160000D03*
Y1200000D03*
X662000Y1183500D03*
X640000Y1280000D03*
X660000D03*
Y1220000D03*
X640000D03*
Y1240000D03*
X660000D03*
X640000Y1260000D03*
X660000D03*
X680000Y1240000D03*
Y1260000D03*
Y1280000D03*
Y1220000D03*
X660000Y1340000D03*
X640000Y1300000D03*
X660000D03*
Y1320000D03*
X640000D03*
X680000Y1340000D03*
Y1300000D03*
Y1320000D03*
X657000Y1331500D03*
X660000Y1420000D03*
X640000D03*
Y1400000D03*
X660000D03*
X640000Y1380000D03*
X680000Y1420000D03*
Y1360000D03*
X660000Y1500000D03*
X640000D03*
X660000Y1480000D03*
X640000D03*
Y1460000D03*
Y1440000D03*
X660000D03*
X680000Y1500000D03*
Y1480000D03*
Y1440000D03*
X662000Y1459000D03*
X634200Y1561200D03*
Y1565700D03*
X639700Y1561200D03*
Y1565700D03*
X646200Y1561200D03*
Y1565700D03*
X651700Y1561200D03*
Y1565700D03*
X640000Y1680000D03*
X660000D03*
X680000D03*
Y1720000D03*
X640000Y1700000D03*
X660000D03*
Y1720000D03*
X640000D03*
Y1660000D03*
X660000D03*
X680000Y1780000D03*
X660000D03*
X640000D03*
X680000Y1760000D03*
X660000D03*
X640000D03*
X680000Y1740000D03*
X660000D03*
X640000D03*
X680000Y1820000D03*
X660000D03*
X680000Y1800000D03*
X660000D03*
X640000D03*
X680000Y1860000D03*
X660000Y1840000D03*
X640000D03*
Y1860000D03*
X660000D03*
X680000Y1880000D03*
Y1900000D03*
Y1920000D03*
X660000Y1880000D03*
X640000D03*
X660000Y1900000D03*
X640000D03*
X660000Y1920000D03*
X640000D03*
Y1940000D03*
X660000D03*
X680000Y1960000D03*
X660000D03*
X640000D03*
X632559Y1986626D03*
X652559D03*
X672559D03*
X660000Y1980000D03*
X640000D03*
X680000D03*
X692559Y1986626D03*
X700000Y20000D03*
X740000Y40000D03*
X750018Y5500D03*
X730018D03*
X710018D03*
X740000Y20000D03*
X720000D03*
X760000Y40000D03*
Y20000D03*
X700000Y120000D03*
X720000D03*
X740000D03*
X700000Y80000D03*
Y60000D03*
Y100000D03*
X720000D03*
Y60000D03*
X740000D03*
Y80000D03*
X720000D03*
X740000Y100000D03*
X760000Y120000D03*
Y100000D03*
Y80000D03*
Y60000D03*
X700000Y180000D03*
X740000D03*
X720000D03*
Y140000D03*
Y160000D03*
X760000D03*
X740000D03*
X700000D03*
Y140000D03*
X740000D03*
X760000D03*
Y180000D03*
X700000Y260000D03*
Y240000D03*
Y220000D03*
Y200000D03*
X720000Y260000D03*
Y240000D03*
Y220000D03*
Y200000D03*
X740000Y260000D03*
Y200000D03*
Y220000D03*
Y240000D03*
X760000Y260000D03*
Y200000D03*
Y220000D03*
Y240000D03*
Y320000D03*
X700000D03*
Y300000D03*
Y280000D03*
X720000Y320000D03*
Y300000D03*
Y280000D03*
X740000D03*
Y300000D03*
X760000Y280000D03*
X740000Y400000D03*
X720000D03*
X700000D03*
X740000Y380000D03*
X720000D03*
X760000Y400000D03*
Y360000D03*
Y380000D03*
Y460000D03*
Y480000D03*
X740000D03*
X720000D03*
X700000D03*
Y420000D03*
X720000D03*
X740000D03*
Y440000D03*
X720000D03*
X700000D03*
Y460000D03*
X720000D03*
X740000D03*
X760000Y420000D03*
Y440000D03*
X720000Y520000D03*
X700000D03*
X740000Y500000D03*
X720000D03*
X740000Y520000D03*
X700000Y500000D03*
Y540000D03*
X740000D03*
X720000D03*
X760000D03*
Y520000D03*
Y500000D03*
Y560000D03*
X720000D03*
X740000D03*
X700000D03*
X740000Y600000D03*
Y580000D03*
X720000D03*
X740000Y620000D03*
X720000D03*
X700000Y580000D03*
Y600000D03*
X720000D03*
X760000Y620000D03*
Y600000D03*
Y580000D03*
Y680000D03*
Y640000D03*
X740000D03*
Y680000D03*
X720000D03*
X700000D03*
Y660000D03*
X720000D03*
X740000D03*
X700000Y640000D03*
X720000D03*
X700000Y720000D03*
X720000D03*
X740000D03*
Y760000D03*
X720000D03*
X700000D03*
Y740000D03*
X720000D03*
X740000D03*
X760000Y760000D03*
Y740000D03*
Y720000D03*
X740000Y840000D03*
X700000D03*
X720000D03*
X740000Y800000D03*
X720000D03*
X700000D03*
Y820000D03*
X720000D03*
X740000D03*
X700000Y780000D03*
X720000D03*
X740000D03*
X760000Y840000D03*
Y800000D03*
Y820000D03*
Y780000D03*
X740000Y920000D03*
X700000D03*
X720000D03*
X740000Y900000D03*
Y880000D03*
Y860000D03*
X700000Y900000D03*
X720000D03*
X700000Y880000D03*
X720000D03*
X700000Y860000D03*
X720000D03*
X760000Y920000D03*
Y900000D03*
Y880000D03*
Y860000D03*
X700000Y980000D03*
X720000D03*
X740000D03*
X700000Y960000D03*
X720000D03*
X740000D03*
X760000Y980000D03*
Y960000D03*
X740000Y1040000D03*
X720000D03*
X700000D03*
X760000D03*
X700000Y1120000D03*
Y1100000D03*
X720000Y1120000D03*
X740000D03*
Y1080000D03*
X700000D03*
X760000Y1120000D03*
X740000Y1160000D03*
X720000D03*
X700000D03*
Y1200000D03*
X720000D03*
X740000D03*
X760000Y1160000D03*
Y1200000D03*
X700000Y1240000D03*
X740000Y1260000D03*
X720000D03*
X700000D03*
X740000Y1280000D03*
X720000D03*
X700000D03*
Y1220000D03*
X720000D03*
X740000D03*
Y1240000D03*
X720000D03*
X760000D03*
Y1260000D03*
Y1280000D03*
Y1220000D03*
X740000Y1340000D03*
X720000D03*
X700000D03*
X740000Y1300000D03*
X720000D03*
X700000D03*
Y1320000D03*
X740000D03*
X720000D03*
X760000Y1340000D03*
Y1300000D03*
Y1320000D03*
X740000Y1420000D03*
X720000D03*
X740000Y1380000D03*
Y1360000D03*
X720000Y1380000D03*
Y1360000D03*
X700000Y1380000D03*
Y1360000D03*
X760000Y1420000D03*
Y1380000D03*
Y1360000D03*
X700000Y1500000D03*
X740000Y1440000D03*
X720000D03*
X700000D03*
X740000Y1480000D03*
X720000D03*
X700000D03*
X760000Y1440000D03*
Y1480000D03*
X740000Y1520000D03*
X720000D03*
X760000D03*
X700000Y1680000D03*
X740000Y1700000D03*
X720000D03*
Y1720000D03*
X740000D03*
Y1680000D03*
X720000D03*
X760000Y1720000D03*
X753500Y1662000D03*
Y1666500D03*
X759000Y1662000D03*
Y1666500D03*
X765500Y1662000D03*
Y1666500D03*
X700000Y1780000D03*
Y1760000D03*
Y1740000D03*
X720000Y1780000D03*
X740000Y1740000D03*
X760000Y1780000D03*
Y1740000D03*
X758000Y1756000D03*
X759700Y1817500D03*
X700000Y1820000D03*
Y1800000D03*
Y1860000D03*
X720000D03*
X740000D03*
X720000Y1800000D03*
X740000D03*
Y1820000D03*
X720000D03*
X759700Y1837500D03*
X720000Y1880000D03*
X740000Y1900000D03*
Y1880000D03*
X700000D03*
Y1900000D03*
Y1920000D03*
X720000Y1940000D03*
Y1900000D03*
Y1920000D03*
X700000Y1940000D03*
X760000Y1880000D03*
Y1940000D03*
X728700Y1933100D03*
X720000Y1960000D03*
X700000D03*
X720000Y1980000D03*
X700000D03*
X712559Y1986626D03*
X732559D03*
X740000Y1960000D03*
Y1980000D03*
X752559Y1986626D03*
X759900Y1959200D03*
X760000Y1980000D03*
X755995Y1968282D03*
X800000Y40000D03*
X820000D03*
X840000D03*
X780000D03*
X810018Y5500D03*
X790018D03*
X770018D03*
X780000Y20000D03*
X800000D03*
X820000D03*
X830018Y5500D03*
X840000Y20000D03*
X800000Y120000D03*
X820000D03*
X840000D03*
X800000Y100000D03*
X820000D03*
X840000D03*
X800000Y80000D03*
X820000D03*
X840000D03*
X800000Y60000D03*
X820000D03*
X840000D03*
X780000Y120000D03*
Y60000D03*
Y80000D03*
Y100000D03*
Y160000D03*
X840000Y140000D03*
X820000D03*
X800000D03*
X816000Y187000D03*
X780000Y140000D03*
Y180000D03*
X828500Y171000D03*
X840000Y174250D03*
X820500Y171000D03*
X792343Y193599D03*
X832500Y171000D03*
X824500D03*
X816500D03*
X820000Y260000D03*
X780000Y200000D03*
Y220000D03*
Y240000D03*
X800000Y220000D03*
Y240000D03*
X820000Y220000D03*
X840000Y240000D03*
X828000Y203000D03*
X792343Y197402D03*
X780000Y300000D03*
X800000Y280000D03*
Y340000D03*
X780000D03*
Y380000D03*
Y360000D03*
Y400000D03*
X820000D03*
X800000D03*
Y380000D03*
Y360000D03*
X840000Y400000D03*
X824335Y365915D03*
X815375Y362750D03*
X836500Y362500D03*
X833000D03*
X840000Y366000D03*
Y362500D03*
X833000Y366000D03*
X836500D03*
X813350Y369250D03*
X780000Y440000D03*
Y420000D03*
Y460000D03*
X800000Y480000D03*
X820000Y420000D03*
Y440000D03*
Y460000D03*
X800000D03*
Y440000D03*
Y420000D03*
X820000Y480000D03*
X780000D03*
X840000D03*
Y420000D03*
Y440000D03*
Y460000D03*
X780000Y540000D03*
X800000D03*
X820000D03*
X780000Y500000D03*
X820000D03*
Y520000D03*
X800000Y500000D03*
Y520000D03*
X780000D03*
X840000Y500000D03*
Y520000D03*
Y540000D03*
X780000Y580000D03*
Y560000D03*
X800000Y600000D03*
Y580000D03*
Y560000D03*
X780000Y620000D03*
X800000D03*
X820000D03*
X780000Y600000D03*
X820000Y580000D03*
Y560000D03*
Y600000D03*
X840000Y620000D03*
Y580000D03*
Y560000D03*
Y600000D03*
X820000Y700000D03*
X780000D03*
X778400Y659800D03*
X800000Y640000D03*
X780000D03*
X820000Y660000D03*
X798400Y659800D03*
X840000Y640000D03*
Y680000D03*
Y660000D03*
Y700000D03*
X782500Y648000D03*
X820000Y720000D03*
X800000Y760000D03*
X780000D03*
Y740000D03*
X800000D03*
Y720000D03*
X780000D03*
X840000D03*
X824335Y771415D03*
X815375Y768250D03*
X840000Y771500D03*
X833000D03*
X836500D03*
X840000Y768000D03*
X836500D03*
X833000D03*
X780000Y840000D03*
X800000D03*
X820000D03*
Y820000D03*
X780000Y800000D03*
Y780000D03*
X800000D03*
X840000Y840000D03*
Y800000D03*
Y820000D03*
X780000Y920000D03*
X800000D03*
X820000D03*
X780000Y900000D03*
X800000D03*
X820000D03*
X780000Y880000D03*
X800000D03*
X820000D03*
X780000Y860000D03*
X800000D03*
X820000D03*
X840000Y920000D03*
Y860000D03*
Y880000D03*
Y900000D03*
X780000Y980000D03*
X800000D03*
X820000D03*
X780000Y960000D03*
X800000D03*
X820000D03*
X840000D03*
Y980000D03*
X800000Y1060000D03*
X820000D03*
X780000D03*
X820000Y1040000D03*
X840000Y1060000D03*
Y1040000D03*
X780000Y1120000D03*
X800000D03*
Y1080000D03*
Y1100000D03*
X820000Y1120000D03*
X800000Y1200000D03*
X820000D03*
X780000Y1160000D03*
X800000D03*
X780000Y1200000D03*
X840000D03*
X824335Y1176915D03*
X815375Y1173750D03*
X836500Y1177000D03*
X833000D03*
X840000D03*
X820000Y1220000D03*
Y1240000D03*
X800000D03*
X780000D03*
X820000Y1260000D03*
X800000D03*
X780000D03*
X820000Y1280000D03*
X800000D03*
X780000D03*
Y1220000D03*
X800000D03*
X840000Y1280000D03*
Y1220000D03*
Y1240000D03*
Y1260000D03*
X820000Y1340000D03*
X800000D03*
X780000D03*
X820000Y1300000D03*
X800000D03*
X780000D03*
Y1320000D03*
X820000D03*
X800000D03*
X840000Y1340000D03*
Y1300000D03*
Y1320000D03*
X820000Y1420000D03*
X800000D03*
X780000D03*
X820000Y1380000D03*
Y1360000D03*
X800000Y1380000D03*
Y1360000D03*
X780000Y1380000D03*
Y1360000D03*
X840000Y1420000D03*
Y1360000D03*
Y1380000D03*
X820000Y1440000D03*
X800000D03*
X780000D03*
X820000Y1480000D03*
X800000D03*
X780000D03*
X840000Y1440000D03*
Y1480000D03*
X800000Y1560000D03*
X780000Y1520000D03*
X840000Y1640000D03*
Y1600000D03*
X824335Y1582415D03*
X816625Y1579250D03*
X840000Y1582500D03*
X833000D03*
X836500D03*
X840000Y1579000D03*
X836500D03*
X833000D03*
X813000Y1585750D03*
X808500Y1621500D03*
X814000D03*
Y1626000D03*
X808500D03*
X814000Y1630500D03*
X808500D03*
X820000Y1680000D03*
X829388Y1695500D03*
X825388D03*
X833388D03*
X837388D03*
X840000Y1680000D03*
Y1660000D03*
X771000Y1662000D03*
Y1666500D03*
X780000Y1780000D03*
X800000D03*
Y1740000D03*
X780000D03*
X795500Y1755000D03*
X825388Y1739500D03*
X829388D03*
X833388D03*
X837388D03*
X837500Y1785000D03*
X829500D03*
X819000D03*
X815000D03*
X816000Y1801000D03*
X780000Y1800000D03*
X800000D03*
X780000Y1840000D03*
X800000Y1820000D03*
X820000D03*
X828000Y1862000D03*
X827500Y1817000D03*
X834750Y1823285D03*
X819000Y1839000D03*
X800000Y1920000D03*
X820000D03*
X780000D03*
X796339Y1937007D03*
X820000Y1980000D03*
X772559Y1986626D03*
X792559D03*
X812559D03*
X769239Y1955776D03*
X780000Y1980000D03*
X800000D03*
X823400Y1973400D03*
X827900D03*
X835900Y1973500D03*
X839400D03*
X832559Y1986626D03*
X840000Y1980000D03*
X799205Y1960532D03*
X774989Y1955708D03*
X780214Y1953257D03*
X796339Y1940507D03*
X804239Y1953307D03*
Y1956807D03*
X800739D03*
Y1953307D03*
X797239D03*
Y1956807D03*
X785239Y1960907D03*
X860000Y40000D03*
X880000D03*
X890018Y5500D03*
X870018D03*
X850018D03*
X880000Y20000D03*
X860000D03*
X900000Y40000D03*
X910018Y5500D03*
X900000Y20000D03*
X860000Y120000D03*
X880000D03*
X860000Y100000D03*
X880000D03*
X860000Y80000D03*
X880000D03*
X860000Y60000D03*
X880000D03*
X900000Y120000D03*
Y60000D03*
Y100000D03*
Y80000D03*
X860000Y140000D03*
X908493Y136513D03*
X880000Y180000D03*
X869250Y144750D03*
X885993Y134893D03*
X885531Y164804D03*
X896441Y147203D03*
X844000Y190000D03*
X866961Y162539D03*
X896547Y150803D03*
X890469Y164804D03*
X864975Y148875D03*
X863441Y219890D03*
X876441Y262165D03*
Y255866D03*
X863307Y264102D03*
X860000Y260000D03*
X876441Y246417D03*
Y236968D03*
Y230669D03*
Y221220D03*
Y211771D03*
X863441Y213102D03*
X860000Y240000D03*
X899941Y233917D03*
Y218917D03*
Y203917D03*
X908654Y231105D03*
X904838D03*
X872500Y241500D03*
X876500Y251000D03*
X901441Y244842D03*
X908346Y235394D03*
X905146D03*
X872941Y223745D03*
Y228145D03*
X867441Y214896D03*
Y218096D03*
Y265290D03*
X901600Y249800D03*
X863307Y269678D03*
X863441Y288972D03*
X863346Y301768D03*
X860100Y336500D03*
X873600Y332200D03*
X860100Y333000D03*
X876441Y318858D03*
Y309409D03*
Y299960D03*
Y290511D03*
Y281063D03*
Y271614D03*
X863346Y307602D03*
X863441Y282602D03*
X901500Y312500D03*
X899941Y283917D03*
Y278917D03*
X856200Y337300D03*
X844050D03*
X872941Y274138D03*
Y278538D03*
Y293036D03*
Y297436D03*
Y311934D03*
Y316334D03*
X867441Y268490D03*
Y284187D03*
Y287387D03*
Y303085D03*
Y306285D03*
X899941Y308917D03*
X865000Y371000D03*
X868500D03*
X876000D03*
X872500D03*
X879600Y385200D03*
X860000Y400000D03*
X880000D03*
X900000D03*
X899900Y382300D03*
X850966Y370025D03*
X843500Y366000D03*
Y362500D03*
X880000Y480000D03*
X860000D03*
X880000Y420000D03*
X860000D03*
X880000Y440000D03*
X860000D03*
X880000Y460000D03*
X860000D03*
X900000Y480000D03*
Y420000D03*
Y440000D03*
Y460000D03*
X907493Y542025D03*
X880000Y500000D03*
X860000D03*
X880000Y520000D03*
X860000D03*
X900000Y500000D03*
Y520000D03*
X872875Y535275D03*
X891250Y537500D03*
X895547Y552715D03*
X857735Y553465D03*
X895547Y556315D03*
X865125Y544000D03*
X863441Y625402D03*
X876441Y626732D03*
Y617283D03*
X863441Y618614D03*
X860000Y580000D03*
Y560000D03*
X880000Y580000D03*
Y600000D03*
X860000D03*
X899941Y624429D03*
Y609429D03*
X900000Y600000D03*
X883781Y564519D03*
X872941Y629257D03*
X867441Y620408D03*
Y623608D03*
X888719Y564519D03*
X863441Y694484D03*
X863287Y669690D03*
X876441Y661378D03*
Y651929D03*
Y642480D03*
Y636181D03*
X863287Y675114D03*
X863441Y688114D03*
X876441Y696023D03*
Y686575D03*
Y677126D03*
Y667677D03*
X899941Y684429D03*
Y639429D03*
X908654Y636613D03*
X904838D03*
X899941Y689429D03*
X868500Y654000D03*
X876500Y648000D03*
X901441Y650354D03*
X908346Y640906D03*
X905146D03*
X872941Y633657D03*
Y679650D03*
Y684050D03*
Y698548D03*
Y702948D03*
X867441Y670802D03*
Y674002D03*
Y689699D03*
Y692899D03*
X901200Y655100D03*
X863397Y713280D03*
X859500Y741800D03*
X876441Y724370D03*
Y714921D03*
Y705472D03*
X863397Y707114D03*
X873400Y738400D03*
X859500Y738300D03*
X901500Y718000D03*
X856100Y743300D03*
X850966Y775525D03*
X843500Y771500D03*
Y768000D03*
X846200Y743300D03*
X872941Y717446D03*
Y721846D03*
X867441Y708597D03*
Y711797D03*
X899941Y714429D03*
X860000Y840000D03*
X880000D03*
X864500Y776500D03*
X868000D03*
X872000D03*
X875500D03*
X860000Y800000D03*
X880000D03*
X860000Y820000D03*
X880000D03*
X900000Y840000D03*
Y800000D03*
Y820000D03*
X860000Y920000D03*
X880000D03*
X860000Y860000D03*
X880000D03*
X860000Y880000D03*
X880000D03*
X860000Y900000D03*
X880000D03*
X900000Y920000D03*
Y860000D03*
Y880000D03*
Y900000D03*
X907493Y947537D03*
X860000Y980000D03*
X886517Y945917D03*
X872875Y940925D03*
X883781Y970031D03*
X895547Y958227D03*
X857623Y958977D03*
X895547Y961827D03*
X888719Y970031D03*
X865125Y949600D03*
X863441Y1030914D03*
X876441Y1066890D03*
Y1057441D03*
Y1047992D03*
Y1041693D03*
Y1032244D03*
Y1022795D03*
X863441Y1024126D03*
X880000Y1000000D03*
X860000Y1040000D03*
X899941Y1044941D03*
Y1029941D03*
Y1014941D03*
X908654Y1042129D03*
X904838D03*
X900000Y1000000D03*
Y1040000D03*
Y1020000D03*
X868500Y1059500D03*
X901441Y1055866D03*
X876500Y1053500D03*
X908346Y1046418D03*
X905146D03*
X872941Y1034769D03*
Y1039169D03*
X867441Y1025920D03*
Y1029120D03*
X901300Y1060700D03*
X863346Y1112792D03*
X863441Y1099996D03*
X863308Y1080702D03*
X876441Y1129882D03*
Y1120433D03*
Y1110984D03*
Y1101535D03*
Y1092087D03*
Y1082638D03*
Y1073189D03*
X863308Y1075126D03*
X863441Y1093626D03*
X863346Y1118626D03*
X899941Y1094941D03*
Y1089941D03*
X900000Y1080000D03*
X901500Y1123500D03*
X872941Y1085162D03*
Y1089562D03*
Y1104060D03*
Y1108460D03*
Y1122958D03*
Y1127358D03*
X867441Y1076314D03*
Y1079514D03*
Y1095211D03*
Y1098411D03*
Y1114109D03*
Y1117309D03*
X899941Y1119941D03*
X859500Y1147600D03*
X874200Y1144000D03*
X859500Y1144100D03*
X864000Y1181900D03*
X867500D03*
X872200D03*
X875700D03*
X860000Y1200000D03*
X880000D03*
X900000D03*
X854500Y1148700D03*
X850600Y1181025D03*
X843500Y1177000D03*
X844600Y1148700D03*
X860000Y1280000D03*
X880000D03*
X860000Y1220000D03*
Y1240000D03*
Y1260000D03*
X880000Y1220000D03*
Y1240000D03*
Y1260000D03*
X900000Y1280000D03*
Y1220000D03*
Y1240000D03*
Y1260000D03*
X907493Y1353048D03*
X880000Y1340000D03*
X860000D03*
Y1300000D03*
Y1320000D03*
X880000D03*
Y1300000D03*
X900000Y1320000D03*
Y1300000D03*
X872875Y1346488D03*
X891250Y1348500D03*
X865125Y1346488D03*
X876441Y1428307D03*
X863441Y1429638D03*
X860000Y1420000D03*
Y1380000D03*
X899941Y1420453D03*
X883219Y1373504D03*
X895647Y1363738D03*
X857688Y1364488D03*
X895647Y1367338D03*
X887438Y1373374D03*
X863286Y1480714D03*
X863441Y1436426D03*
X876441Y1478701D03*
Y1472402D03*
Y1462953D03*
Y1453504D03*
Y1447205D03*
Y1437756D03*
X860000Y1440000D03*
X876441Y1497599D03*
Y1488150D03*
X863286Y1486138D03*
X863441Y1499138D03*
X899941Y1450453D03*
Y1435453D03*
X908654Y1447641D03*
X904838D03*
X899941Y1500453D03*
Y1495453D03*
X868500Y1465000D03*
X901441Y1461378D03*
X876500Y1459000D03*
X908346Y1451930D03*
X905146D03*
X872941Y1440281D03*
Y1444681D03*
Y1490674D03*
Y1495074D03*
X867441Y1431432D03*
Y1434632D03*
Y1481826D03*
Y1485026D03*
Y1500723D03*
X901400Y1466100D03*
X863347Y1518304D03*
X863441Y1505508D03*
X859500Y1553200D03*
X876441Y1535394D03*
Y1525945D03*
Y1516496D03*
Y1507047D03*
X863347Y1524138D03*
X873300Y1549100D03*
X859500Y1549700D03*
X901500Y1529000D03*
X855500Y1554300D03*
X845600D03*
X872941Y1509572D03*
Y1513972D03*
Y1528470D03*
Y1532870D03*
X867441Y1503923D03*
Y1519621D03*
Y1522821D03*
X899941Y1525453D03*
X860000Y1640000D03*
Y1580000D03*
X865500Y1589000D03*
X869000D03*
X873000D03*
X876500D03*
X880000Y1599000D03*
X900000Y1600000D03*
X850966Y1586525D03*
X843500Y1582500D03*
Y1579000D03*
X891500Y1712000D03*
X895500D03*
Y1708000D03*
X841388Y1695500D03*
X873962Y1672000D03*
Y1676500D03*
Y1681500D03*
Y1685500D03*
X860000Y1660000D03*
X906000Y1713500D03*
X885750Y1701500D03*
X891500Y1708000D03*
X891000Y1720000D03*
X901500Y1681500D03*
X881353Y1650749D03*
X877853D03*
Y1654249D03*
X881353D03*
X896500Y1681000D03*
X859500Y1696000D03*
X886600Y1756100D03*
X872875Y1751600D03*
X906500Y1734100D03*
X907493Y1758560D03*
X898500Y1734000D03*
X910500Y1734600D03*
X895547Y1769250D03*
X883781Y1781054D03*
X895547Y1772850D03*
X888719Y1781054D03*
X865125Y1751800D03*
X902500Y1734000D03*
X910500Y1724700D03*
X863441Y1841938D03*
X876441Y1859016D03*
Y1852717D03*
X860000Y1860000D03*
X876441Y1843268D03*
Y1833819D03*
X863441Y1835150D03*
X899941Y1855965D03*
X908654Y1853153D03*
X904838D03*
X899941Y1840965D03*
Y1825965D03*
X876000Y1864000D03*
X901441Y1866890D03*
X908346Y1857442D03*
X905146D03*
X872941Y1845793D03*
Y1850193D03*
X867441Y1836944D03*
Y1840144D03*
X863346Y1923816D03*
X863441Y1911020D03*
X863287Y1886226D03*
X876441Y1912559D03*
Y1903111D03*
Y1893662D03*
Y1884213D03*
Y1877914D03*
Y1868465D03*
X863287Y1891650D03*
X863441Y1904650D03*
X860000Y1880000D03*
X876441Y1931457D03*
Y1922008D03*
X863346Y1929650D03*
X901500Y1934500D03*
X899941Y1905965D03*
Y1900965D03*
X867500Y1870000D03*
X872941Y1896186D03*
Y1900586D03*
Y1915084D03*
Y1919484D03*
Y1933982D03*
Y1938382D03*
X867441Y1887338D03*
Y1890538D03*
Y1906235D03*
Y1909435D03*
Y1925133D03*
Y1928333D03*
X899941Y1930965D03*
X901200Y1871600D03*
X876441Y1940906D03*
X843500Y1973500D03*
X847000D03*
X852559Y1986626D03*
X872559D03*
X896546Y1986566D03*
X860000Y1980000D03*
X912559Y1986626D03*
X844800Y1949700D03*
X858800Y1951300D03*
X879500Y1970000D03*
X880000Y1955500D03*
X862000Y1969900D03*
Y1960500D03*
X844700Y1945200D03*
X960000Y40000D03*
X940000D03*
X920000D03*
X950018Y5500D03*
X930018D03*
X920000Y20000D03*
X940000D03*
X960000D03*
X980000Y40000D03*
X970018Y5500D03*
X980000Y20000D03*
X960000Y120000D03*
X940000D03*
X920000D03*
Y60000D03*
X940000D03*
X960000D03*
X920000Y100000D03*
X940000D03*
X960000D03*
Y80000D03*
X940000D03*
X920000D03*
X980000Y120000D03*
Y60000D03*
Y100000D03*
Y80000D03*
X960000Y140000D03*
X940000D03*
X960000Y160000D03*
X940000D03*
Y180000D03*
X960000D03*
X980000D03*
X926347Y155500D03*
Y160000D03*
Y164453D03*
X921400Y235002D03*
Y245200D03*
X940000Y200000D03*
X960000D03*
Y220000D03*
X940000D03*
Y240000D03*
X960000D03*
Y260000D03*
X940000D03*
X980000Y240000D03*
Y260000D03*
Y200000D03*
Y220000D03*
X918846Y238501D03*
Y241701D03*
X940000Y280000D03*
X920000D03*
X960000D03*
X920000Y300000D03*
X940000D03*
X960000D03*
X920000Y320000D03*
X940000D03*
X960000D03*
X980000Y280000D03*
Y300000D03*
Y320000D03*
X960000Y400000D03*
X940000D03*
X920000D03*
X960000Y340000D03*
X940000D03*
X920000D03*
Y360000D03*
X940000D03*
X960000D03*
Y380000D03*
X940000D03*
X920000D03*
X980000Y400000D03*
Y340000D03*
Y360000D03*
Y380000D03*
X920000Y480000D03*
X940000D03*
X960000D03*
X920000Y420000D03*
X940000D03*
X960000D03*
X920000Y440000D03*
X940000D03*
X960000D03*
X920000Y460000D03*
X940000D03*
X960000D03*
X980000Y480000D03*
Y420000D03*
Y440000D03*
Y460000D03*
X920000Y500000D03*
X940000D03*
X960000D03*
X920000Y520000D03*
X940000D03*
X960000D03*
Y540000D03*
X980000Y500000D03*
Y520000D03*
Y540000D03*
X940000Y620000D03*
X960000D03*
Y560000D03*
Y580000D03*
Y600000D03*
X940000Y580000D03*
Y600000D03*
X920000Y580000D03*
Y600000D03*
X980000Y620000D03*
Y560000D03*
Y580000D03*
Y600000D03*
X926365Y561000D03*
Y569965D03*
Y565500D03*
X919000Y639715D03*
X920000Y700000D03*
X919000Y651511D03*
X940000Y640000D03*
X960000D03*
X920000Y680000D03*
X940000D03*
X960000D03*
Y660000D03*
X940000D03*
X920000D03*
X940000Y700000D03*
X960000D03*
X980000Y640000D03*
Y660000D03*
Y700000D03*
X918846Y644013D03*
Y647213D03*
X940000Y760000D03*
X960000D03*
X920000D03*
Y740000D03*
Y720000D03*
X940000D03*
X960000D03*
X940000Y740000D03*
X960000D03*
X980000Y760000D03*
Y720000D03*
Y740000D03*
X940000Y840000D03*
X960000D03*
X920000D03*
X940000Y780000D03*
X960000D03*
X940000Y800000D03*
X960000D03*
X940000Y820000D03*
X960000D03*
X920000Y800000D03*
Y820000D03*
Y780000D03*
X980000Y840000D03*
Y780000D03*
Y800000D03*
Y820000D03*
X940000Y920000D03*
X960000D03*
X920000D03*
X940000Y860000D03*
X960000D03*
X940000Y880000D03*
X960000D03*
X940000Y900000D03*
X960000D03*
X920000Y860000D03*
Y880000D03*
Y900000D03*
X980000Y920000D03*
Y860000D03*
Y880000D03*
Y900000D03*
X960000Y980000D03*
Y940000D03*
X940000D03*
X960000Y960000D03*
X980000Y980000D03*
Y940000D03*
Y960000D03*
X926477Y966500D03*
Y971000D03*
Y975477D03*
X922900Y1048050D03*
Y1054200D03*
X920000Y1060000D03*
X940000D03*
X960000D03*
Y1000000D03*
X940000D03*
X920000D03*
Y1020000D03*
X940000D03*
X960000D03*
Y1040000D03*
X940000D03*
X920000D03*
X980000Y1000000D03*
Y1020000D03*
Y1040000D03*
X918846Y1049525D03*
Y1052725D03*
X940000Y1140000D03*
X960000D03*
X920000Y1080000D03*
X940000D03*
X960000D03*
Y1100000D03*
X940000D03*
X920000Y1120000D03*
X940000D03*
X960000D03*
X920000Y1140000D03*
X980000D03*
Y1100000D03*
X979962Y1075211D03*
X980000Y1120000D03*
X923000Y1160200D03*
X940000Y1160000D03*
X960000D03*
Y1180000D03*
X940000D03*
X923000Y1180200D03*
X960000Y1200000D03*
X940000D03*
X920000D03*
X980000Y1160000D03*
Y1180000D03*
Y1200000D03*
X960000Y1280000D03*
X940000D03*
X920000D03*
X960000Y1220000D03*
X940000D03*
X960000Y1240000D03*
X940000D03*
X960000Y1260000D03*
X940000D03*
X920000Y1220000D03*
Y1240000D03*
Y1260000D03*
X980000Y1220000D03*
Y1240000D03*
Y1260000D03*
Y1280000D03*
X960000Y1340000D03*
X940000D03*
X920000D03*
X960000Y1300000D03*
X940000D03*
X960000Y1320000D03*
X940000D03*
X920000Y1300000D03*
Y1320000D03*
X980000Y1340000D03*
Y1300000D03*
Y1320000D03*
X981700Y1409000D03*
X954300Y1412600D03*
X960000Y1360000D03*
Y1380000D03*
Y1400000D03*
X940000D03*
X920000D03*
X963500Y1409000D03*
X973000D03*
X968000D03*
X977500D03*
X980000Y1360000D03*
Y1380000D03*
Y1400000D03*
X926300Y1372000D03*
Y1380988D03*
Y1376500D03*
X919000Y1450734D03*
Y1462540D03*
X920000Y1480000D03*
Y1440000D03*
X918846Y1455037D03*
Y1458237D03*
X920000Y1520000D03*
Y1540000D03*
X923800Y1559300D03*
X923500Y1579800D03*
X920000Y1600000D03*
X959000Y1631000D03*
X943500Y1646989D03*
X973000Y1641500D03*
X931000Y1659000D03*
X960000Y1700000D03*
Y1720000D03*
X933000Y1704000D03*
X951500Y1658000D03*
X952000Y1678000D03*
X980000Y1700000D03*
Y1720000D03*
X963500Y1675000D03*
Y1657000D03*
X959000D03*
Y1675000D03*
X926500Y1660000D03*
X941000Y1653000D03*
X934825Y1682285D03*
X947000Y1654500D03*
X915250Y1687500D03*
X919250Y1711500D03*
X960000Y1740000D03*
Y1760000D03*
X940000D03*
X933000Y1736500D03*
X925500Y1738000D03*
X960000Y1780000D03*
X980000D03*
Y1740000D03*
Y1760000D03*
X916500Y1729500D03*
X926400Y1777500D03*
Y1782000D03*
Y1786500D03*
X921900Y1722400D03*
X919000Y1856251D03*
X960000Y1860000D03*
X940000D03*
X960000Y1800000D03*
X940000D03*
X920000D03*
X940000Y1820000D03*
X960000D03*
X940000Y1840000D03*
X960000D03*
X920000D03*
X980000Y1860000D03*
Y1800000D03*
Y1820000D03*
Y1840000D03*
X918846Y1860549D03*
Y1863749D03*
X920000Y1920000D03*
X940000D03*
X960000D03*
Y1940000D03*
X940000D03*
X920000D03*
X919000Y1868047D03*
X960000Y1880000D03*
X940000D03*
X920000D03*
X960000Y1900000D03*
X940000D03*
X920000D03*
X980000Y1920000D03*
Y1940000D03*
X980018Y1897856D03*
X932559Y1986626D03*
X952559D03*
X960000Y1960000D03*
X940000D03*
X920000D03*
Y1980000D03*
X940000D03*
X960000D03*
X972559Y1986626D03*
X980000Y1960000D03*
Y1980000D03*
X1031902Y43616D03*
X1020000Y40000D03*
X1000000D03*
X1031902Y23616D03*
X1030018Y5500D03*
X1010018D03*
X990018D03*
X1000000Y20000D03*
X1020000D03*
Y120000D03*
X1000000D03*
X1031902Y63616D03*
Y103616D03*
Y83616D03*
X1000000Y60000D03*
X1020000D03*
X1000000Y100000D03*
X1020000D03*
Y80000D03*
X1000000D03*
X1031902Y143616D03*
Y123616D03*
Y163616D03*
X1020000Y140000D03*
Y160000D03*
Y180000D03*
X1031902Y183616D03*
X1000000Y240000D03*
X1020000D03*
X1031902Y263616D03*
X1020000Y260000D03*
X1000000D03*
X1031902Y223616D03*
Y203616D03*
Y243616D03*
X1000000Y200000D03*
X1020000D03*
Y220000D03*
X1000000D03*
X1031902Y303616D03*
Y283616D03*
Y323616D03*
X1000000Y280000D03*
X1020000D03*
X1000000Y300000D03*
X1020000D03*
X1000000Y320000D03*
X1020000D03*
X1031902Y403616D03*
X1020000Y400000D03*
X1000000D03*
X1031902Y383616D03*
Y363616D03*
Y343616D03*
X1020000Y340000D03*
X1000000D03*
Y360000D03*
X1020000D03*
Y380000D03*
X1000000D03*
X1031902Y483616D03*
X1000000Y480000D03*
X1020000D03*
X1031902Y443616D03*
Y423616D03*
Y463616D03*
X1000000Y420000D03*
X1020000D03*
X1000000Y440000D03*
X1020000D03*
X1000000Y460000D03*
X1020000D03*
X1031902Y523616D03*
Y503616D03*
Y543616D03*
X1000000Y500000D03*
X1020000D03*
X1000000Y520000D03*
X1020000D03*
X1000000Y540000D03*
X1020000D03*
X1031902Y623616D03*
X1000000Y620000D03*
X1020000D03*
X1031902Y603616D03*
Y583616D03*
Y563616D03*
X1020000Y560000D03*
X1000000D03*
X1020000Y580000D03*
X1000000D03*
X1020000Y600000D03*
X1000000D03*
X1031902Y683616D03*
Y663616D03*
Y643616D03*
X1000000Y640000D03*
X1020000D03*
Y660000D03*
Y680000D03*
Y700000D03*
X1000000Y740000D03*
X1020000D03*
X1000000Y760000D03*
X1020000D03*
X1031902Y763616D03*
Y743616D03*
Y723616D03*
Y703616D03*
X1000000Y720000D03*
X1020000D03*
X1031902Y843616D03*
X1000000Y840000D03*
X1020000D03*
X1031902Y823616D03*
Y803616D03*
Y783616D03*
X1000000Y780000D03*
X1020000D03*
X1000000Y800000D03*
X1020000D03*
X1000000Y820000D03*
X1020000D03*
X1000000Y920000D03*
X1020000D03*
X1031902Y903616D03*
Y883616D03*
Y863616D03*
X1000000Y860000D03*
X1020000D03*
X1000000Y880000D03*
X1020000D03*
X1000000Y900000D03*
X1020000D03*
X1031902Y983616D03*
X1000000Y980000D03*
X1020000D03*
X1031902Y963616D03*
Y943616D03*
Y923616D03*
X1020000Y940000D03*
X1000000D03*
Y960000D03*
X1020000D03*
X1031902Y1063616D03*
X1020000Y1060000D03*
X1031902Y1043616D03*
Y1023616D03*
Y1003616D03*
X1020000Y1000000D03*
X1000000D03*
Y1020000D03*
X1020000D03*
Y1040000D03*
X1000000D03*
X1031902Y1123616D03*
X1000000Y1140000D03*
X1020000D03*
X1031902Y1103616D03*
Y1083616D03*
X1020000Y1080000D03*
Y1100000D03*
X999922Y1102598D03*
X1000000Y1120000D03*
X1020000D03*
X1031902Y1143616D03*
Y1183616D03*
Y1163616D03*
X1000000Y1160000D03*
X1020000D03*
Y1180000D03*
X1000000D03*
X1031902Y1203616D03*
X1020000Y1200000D03*
X1000000D03*
Y1220000D03*
X1020000Y1240000D03*
X1000000D03*
X1020000Y1260000D03*
X1000000D03*
X1031902Y1283616D03*
X1020000Y1280000D03*
X1000000D03*
X1031902Y1263616D03*
Y1243616D03*
Y1223616D03*
X1020000Y1220000D03*
X1031902Y1343616D03*
X1020000Y1340000D03*
X1000000D03*
X1031902Y1323616D03*
Y1303616D03*
X1020000Y1300000D03*
X1000000D03*
X1020000Y1320000D03*
X1000000D03*
X986200Y1409000D03*
X994600Y1414100D03*
X990300Y1412500D03*
X1031902Y1363616D03*
Y1383616D03*
X1020000Y1360000D03*
X1000000D03*
Y1380000D03*
X1020000D03*
Y1400000D03*
X1000000D03*
X994898Y1646102D03*
X992500Y1636000D03*
X991602Y1622500D03*
X1000000Y1700000D03*
X1020000Y1720000D03*
X1000000D03*
X995102Y1676102D03*
X995000Y1656102D03*
Y1666102D03*
X1031902Y1785969D03*
X1000000Y1780000D03*
X1020000D03*
X1031902Y1745969D03*
Y1725969D03*
Y1765969D03*
X1000000Y1740000D03*
X1020000D03*
Y1760000D03*
X1000000D03*
X1031902Y1865969D03*
Y1845969D03*
X1020000Y1860000D03*
X1000000D03*
X1031902Y1805969D03*
Y1825969D03*
X1020000Y1800000D03*
X1000000D03*
Y1820000D03*
X1020000D03*
X1000000Y1840000D03*
X1020000D03*
X1031902Y1925969D03*
X999469Y1923465D03*
X1020000Y1920000D03*
Y1940000D03*
X1000000D03*
X1031902Y1885969D03*
Y1905969D03*
X1020000Y1880000D03*
Y1900000D03*
X1031902Y1965969D03*
Y1945969D03*
X992559Y1986626D03*
X1012559D03*
X1031902Y1985969D03*
X1020000Y1960000D03*
X1000000D03*
Y1980000D03*
X1020000D03*
G54D21*
X1009744Y1646102D03*
Y1641102D03*
Y1636102D03*
Y1631102D03*
Y1626102D03*
Y1621102D03*
Y1676102D03*
Y1671102D03*
Y1666102D03*
Y1661102D03*
Y1656102D03*
Y1651102D03*
G54D22*
G01X1008244Y1621102D02*
X993000D01*
X991602Y1622500D01*
G01X1008244Y1656102D02*
X995000D01*
G01X1008244Y1676102D02*
X995102D01*
G54D13*
X23426Y281496D03*
X24764Y286496D03*
X28426Y290197D03*
X38465D03*
X42166Y286496D03*
X11615Y1922835D03*
X12953Y1927835D03*
X16615Y1931536D03*
X26654D03*
X30355Y1927835D03*
X31693Y1922835D03*
X43504Y281496D03*
X123819Y17717D03*
X125157Y22717D03*
X128819Y26418D03*
X138858D03*
X142559Y22717D03*
X143897Y17717D03*
X265552Y279528D03*
X266890Y284528D03*
X270552Y288229D03*
X280591D03*
X284292Y284528D03*
X285630Y279528D03*
X265552Y685030D03*
X266890Y690030D03*
X270552Y693731D03*
X280591D03*
X284292Y690030D03*
X285630Y685030D03*
X265552Y1088573D03*
X266890Y1093573D03*
X270552Y1097274D03*
X280591D03*
X284292Y1093573D03*
X285630Y1088573D03*
X265552Y1903534D03*
X266890Y1908534D03*
X270552Y1912235D03*
X280591D03*
X284292Y1908534D03*
X285630Y1903534D03*
X987992Y163376D03*
Y686998D03*
Y1082667D03*
Y1903534D03*
X989330Y168376D03*
X992992Y172077D03*
X1003031D03*
X1006732Y168376D03*
X1008070Y163376D03*
X989330Y691998D03*
X992992Y695699D03*
X1003031D03*
X1006732Y691998D03*
X1008070Y686998D03*
X989330Y1087667D03*
X992992Y1091368D03*
X1003031D03*
X1006732Y1087667D03*
X1008070Y1082667D03*
X989330Y1908534D03*
X992992Y1912235D03*
X1003031D03*
X1006732Y1908534D03*
X1008070Y1903534D03*
G54D23*
G01X-90900Y-277455D02*
Y-294955D01*
X-82166D01*
G01X-69033Y-283289D02*
Y-294955D01*
G01Y-278622D02*
X-69470Y-278330D01*
Y-277747D01*
X-69033Y-277455D01*
X-68596Y-277747D01*
Y-278330D01*
X-69033Y-278622D01*
G01X-54590Y-299330D02*
X-53061Y-300497D01*
X-51315Y-300788D01*
X-49787Y-300497D01*
X-48476Y-299039D01*
X-47603Y-296997D01*
Y-283289D01*
G01Y-285622D02*
X-48476Y-284455D01*
X-49787Y-283580D01*
X-51315Y-283289D01*
X-53061Y-283872D01*
X-54153Y-285038D01*
X-55027Y-287080D01*
X-55463Y-289122D01*
X-55245Y-290872D01*
X-54371Y-292914D01*
X-53061Y-294372D01*
X-51315Y-294955D01*
X-50005Y-294663D01*
X-48476Y-293497D01*
X-47603Y-292331D01*
G01X-37745Y-294955D02*
Y-277455D01*
G01Y-285913D02*
X-36653Y-284455D01*
X-35561Y-283580D01*
X-33815Y-283289D01*
X-32505Y-283580D01*
X-30976Y-284747D01*
X-30321Y-286497D01*
Y-294955D01*
G01X-16533Y-277455D02*
Y-294955D01*
G01X-19590Y-283289D02*
X-13476D01*
G01X-2745Y-294955D02*
Y-283289D01*
G01Y-286205D02*
X-1871Y-284747D01*
X-561Y-283580D01*
X1185Y-283289D01*
X2713Y-283580D01*
X4024Y-284747D01*
X4679Y-286788D01*
Y-294955D01*
G01X18467Y-283289D02*
Y-294955D01*
G01Y-278622D02*
X18030Y-278330D01*
Y-277747D01*
X18467Y-277455D01*
X18904Y-277747D01*
Y-278330D01*
X18467Y-278622D01*
G01X32255Y-294955D02*
Y-283289D01*
G01Y-286205D02*
X33129Y-284747D01*
X34439Y-283580D01*
X36185Y-283289D01*
X37713Y-283580D01*
X39024Y-284747D01*
X39679Y-286788D01*
Y-294955D01*
G01X50410Y-299330D02*
X51939Y-300497D01*
X53685Y-300788D01*
X55213Y-300497D01*
X56524Y-299039D01*
X57397Y-296997D01*
Y-283289D01*
G01Y-285622D02*
X56524Y-284455D01*
X55213Y-283580D01*
X53685Y-283289D01*
X51939Y-283872D01*
X50847Y-285038D01*
X49973Y-287080D01*
X49537Y-289122D01*
X49755Y-290872D01*
X50629Y-292914D01*
X51939Y-294372D01*
X53685Y-294955D01*
X54995Y-294663D01*
X56524Y-293497D01*
X57397Y-292331D01*
G01X84100Y-294955D02*
Y-277455D01*
X89340D01*
X91087Y-278330D01*
X92397Y-280372D01*
X92834Y-282705D01*
X92397Y-285038D01*
X91305Y-286788D01*
X89340Y-287664D01*
X84100D01*
G01X101164Y-294955D02*
Y-277455D01*
X105530D01*
X107277Y-278330D01*
X108587Y-279497D01*
X109679Y-281246D01*
X110552Y-283289D01*
X110770Y-286205D01*
X110552Y-289122D01*
X109679Y-291164D01*
X108587Y-292914D01*
X107277Y-294080D01*
X105530Y-294955D01*
X101164D01*
G01X119100D02*
Y-277455D01*
X124340D01*
X126087Y-278330D01*
X127397Y-280372D01*
X127834Y-282705D01*
X127397Y-285038D01*
X126305Y-286788D01*
X124340Y-287664D01*
X119100D01*
G01X142713Y-285622D02*
X143587Y-284747D01*
X144242Y-283289D01*
X144679Y-281246D01*
X144242Y-279497D01*
X143369Y-278330D01*
X141840Y-277455D01*
X135945D01*
Y-294955D01*
X143150D01*
X144679Y-293789D01*
X145552Y-292038D01*
X145989Y-289997D01*
X145552Y-287955D01*
X144242Y-286205D01*
X142713Y-285622D01*
X135945D01*
G01X171600Y-294955D02*
Y-277455D01*
X176840D01*
X178587Y-278330D01*
X179897Y-280372D01*
X180334Y-282705D01*
X179897Y-285038D01*
X178805Y-286788D01*
X176840Y-287664D01*
X171600D01*
G01X188008Y-277455D02*
X193467Y-294955D01*
X198926Y-277455D01*
G01X210967D02*
Y-294955D01*
G01X205945Y-277455D02*
X215989D01*
G01X21540Y-249955D02*
Y-232455D01*
X27217Y-247038D01*
X32894Y-232455D01*
Y-249955D01*
G01X44717D02*
X43407Y-249663D01*
X42097Y-248497D01*
X41223Y-246455D01*
X40787Y-244122D01*
X41223Y-241788D01*
X42097Y-239747D01*
X43407Y-238580D01*
X44717Y-238289D01*
X46027Y-238580D01*
X47337Y-239747D01*
X48210Y-241788D01*
X48429Y-244122D01*
X48210Y-246455D01*
X47337Y-248497D01*
X46027Y-249663D01*
X44717Y-249955D01*
G01X66147Y-232455D02*
Y-249955D01*
G01Y-247331D02*
X65274Y-248789D01*
X63963Y-249663D01*
X62435Y-249955D01*
X60689Y-249372D01*
X59379Y-247914D01*
X58505Y-246164D01*
X58287Y-244122D01*
X58505Y-242080D01*
X59379Y-240330D01*
X60689Y-238872D01*
X62435Y-238289D01*
X63963Y-238580D01*
X65055Y-239164D01*
X66147Y-240330D01*
G01X76442Y-242080D02*
X83429D01*
X82774Y-240038D01*
X81682Y-238872D01*
X80154Y-238289D01*
X78625Y-238580D01*
X77315Y-239455D01*
X76442Y-241497D01*
X76005Y-243247D01*
Y-244997D01*
X76442Y-246747D01*
X77534Y-248497D01*
X78844Y-249663D01*
X80372Y-249955D01*
X81900Y-249372D01*
X83429Y-247622D01*
G01X97217Y-249955D02*
Y-232455D01*
G01X252500Y-249955D02*
Y-232455D01*
X257740D01*
X259487Y-233330D01*
X260797Y-235372D01*
X261234Y-237705D01*
X260797Y-240038D01*
X259705Y-241788D01*
X257740Y-242664D01*
X252500D01*
G01X279170Y-233914D02*
X277860Y-233038D01*
X276332Y-232455D01*
X274585D01*
X272620Y-233330D01*
X271092Y-234788D01*
X270000Y-236539D01*
X269127Y-239455D01*
X268908Y-242080D01*
X269345Y-244705D01*
X270000Y-246455D01*
X271310Y-248205D01*
X272839Y-249372D01*
X274367Y-249955D01*
X275895D01*
X277424Y-249372D01*
X278734Y-248497D01*
X279826Y-247331D01*
G01X293613Y-240622D02*
X294487Y-239747D01*
X295142Y-238289D01*
X295579Y-236246D01*
X295142Y-234497D01*
X294269Y-233330D01*
X292740Y-232455D01*
X286845D01*
Y-249955D01*
X294050D01*
X295579Y-248789D01*
X296452Y-247038D01*
X296889Y-244997D01*
X296452Y-242955D01*
X295142Y-241205D01*
X293613Y-240622D01*
X286845D01*
G01X302817Y-255788D02*
X315917D01*
G01X321845Y-249955D02*
Y-232455D01*
X331889Y-249955D01*
Y-232455D01*
G01X344367Y-249955D02*
X342620Y-249663D01*
X341092Y-248497D01*
X339782Y-246747D01*
X338908Y-244705D01*
X338472Y-242372D01*
Y-240038D01*
X338908Y-237705D01*
X339782Y-235663D01*
X341092Y-233914D01*
X342620Y-232747D01*
X344367Y-232455D01*
X346113Y-232747D01*
X347642Y-233914D01*
X348952Y-235663D01*
X349826Y-237705D01*
X350262Y-240038D01*
Y-242372D01*
X349826Y-244705D01*
X348952Y-246747D01*
X347642Y-248497D01*
X346113Y-249663D01*
X344367Y-249955D01*
G01X265617Y-294955D02*
Y-277455D01*
X262997Y-280955D01*
G01Y-294955D02*
X268237D01*
G01X278314Y-292331D02*
X279623Y-293789D01*
X281152Y-294663D01*
X283117Y-294955D01*
X285082Y-294372D01*
X286610Y-293205D01*
X287702Y-291164D01*
X287920Y-288830D01*
X287484Y-286497D01*
X286392Y-285038D01*
X284863Y-283872D01*
X283335Y-283580D01*
X281807Y-283872D01*
X279842Y-285038D01*
X280497Y-277455D01*
X286392D01*
G01X296469Y-287664D02*
X297997Y-285622D01*
X299307Y-284455D01*
X301054Y-283872D01*
X302582Y-284455D01*
X303674Y-285622D01*
X304547Y-287372D01*
X304765Y-289413D01*
X304547Y-291164D01*
X303674Y-292914D01*
X302363Y-294372D01*
X300835Y-294955D01*
X299089Y-294372D01*
X297560Y-292622D01*
X296687Y-289997D01*
X296469Y-287080D01*
X296905Y-283289D01*
X297560Y-281246D01*
X298652Y-279205D01*
X300180Y-277747D01*
X301709Y-277455D01*
X303237Y-278038D01*
X304329Y-279497D01*
G01X313969Y-287664D02*
X315497Y-285622D01*
X316807Y-284455D01*
X318554Y-283872D01*
X320082Y-284455D01*
X321174Y-285622D01*
X322047Y-287372D01*
X322265Y-289413D01*
X322047Y-291164D01*
X321174Y-292914D01*
X319863Y-294372D01*
X318335Y-294955D01*
X316589Y-294372D01*
X315060Y-292622D01*
X314187Y-289997D01*
X313969Y-287080D01*
X314405Y-283289D01*
X315060Y-281246D01*
X316152Y-279205D01*
X317680Y-277747D01*
X319209Y-277455D01*
X320737Y-278038D01*
X321829Y-279497D01*
G01X331905Y-292914D02*
X333434Y-294372D01*
X335180Y-294955D01*
X336927Y-294372D01*
X338455Y-292622D01*
X339547Y-289997D01*
X339984Y-287372D01*
Y-284164D01*
X339547Y-281539D01*
X338455Y-279205D01*
X337145Y-278038D01*
X335617Y-277455D01*
X333870Y-278038D01*
X332560Y-279205D01*
X331687Y-280955D01*
X331250Y-283289D01*
X331687Y-285330D01*
X332779Y-287372D01*
X334089Y-288539D01*
X335617Y-288830D01*
X337363Y-288247D01*
X338674Y-286788D01*
X339984Y-284164D01*
G01X395208Y-232455D02*
X400667Y-249955D01*
X406126Y-232455D01*
G01X422534Y-249955D02*
X413800D01*
Y-232455D01*
X422534D01*
G01X419040Y-240913D02*
X413800D01*
G01X431300Y-249955D02*
Y-232455D01*
X436759D01*
X438505Y-233330D01*
X439597Y-234497D01*
X440034Y-236830D01*
X439597Y-239164D01*
X438287Y-240622D01*
X436759Y-241497D01*
X431300D01*
G01X436759D02*
X440034Y-249955D01*
G01X453167Y-250538D02*
X452730Y-250247D01*
Y-249663D01*
X453167Y-249372D01*
X453604Y-249663D01*
Y-250247D01*
X453167Y-250538D01*
G01X426917Y-294955D02*
Y-277455D01*
X424297Y-280955D01*
G01Y-294955D02*
X429537D01*
G01X528750Y-232455D02*
Y-249955D01*
X537484D01*
G01X554547D02*
Y-238289D01*
G01Y-240330D02*
X553674Y-239164D01*
X552363Y-238580D01*
X550835Y-238289D01*
X549307Y-238872D01*
X547997Y-240038D01*
X547123Y-241788D01*
X546687Y-244122D01*
X547123Y-246455D01*
X547997Y-248205D01*
X549307Y-249372D01*
X550835Y-249955D01*
X552363Y-249663D01*
X553674Y-248789D01*
X554547Y-247622D01*
G01X563532Y-255205D02*
X564842Y-255788D01*
X566589Y-255205D01*
X567680Y-254039D01*
X568554Y-252580D01*
X569863Y-247914D01*
X572702Y-238289D01*
G01X565715D02*
X569863Y-247914D01*
G01X582342Y-242080D02*
X589329D01*
X588674Y-240038D01*
X587582Y-238872D01*
X586054Y-238289D01*
X584525Y-238580D01*
X583215Y-239455D01*
X582342Y-241497D01*
X581905Y-243247D01*
Y-244997D01*
X582342Y-246747D01*
X583434Y-248497D01*
X584744Y-249663D01*
X586272Y-249955D01*
X587800Y-249372D01*
X589329Y-247622D01*
G01X600060Y-249955D02*
Y-238289D01*
G01Y-240622D02*
X601152Y-239455D01*
X602244Y-238580D01*
X603772Y-238289D01*
X604863Y-238580D01*
X606174Y-239455D01*
G01X581234Y-277455D02*
Y-294955D01*
X572500D01*
G01X559367D02*
X557839Y-294663D01*
X556092Y-293789D01*
X555000Y-292331D01*
X554564Y-290288D01*
X555000Y-288247D01*
X556310Y-286497D01*
X558275Y-285622D01*
X560459D01*
X561769Y-285038D01*
X562861Y-283580D01*
X563297Y-281539D01*
X562642Y-279497D01*
X561114Y-278038D01*
X559367Y-277455D01*
X557621Y-278038D01*
X556092Y-279497D01*
X555437Y-281539D01*
X555874Y-283580D01*
X556965Y-285038D01*
X558275Y-285622D01*
X560459D01*
X562424Y-286497D01*
X563734Y-288247D01*
X564170Y-290288D01*
X563734Y-292331D01*
X562642Y-293789D01*
X560895Y-294663D01*
X559367Y-294955D01*
G01X670864Y-249955D02*
Y-232455D01*
X675230D01*
X676977Y-233330D01*
X678287Y-234497D01*
X679379Y-236246D01*
X680252Y-238289D01*
X680470Y-241205D01*
X680252Y-244122D01*
X679379Y-246164D01*
X678287Y-247914D01*
X676977Y-249080D01*
X675230Y-249955D01*
X670864D01*
G01X689892Y-242080D02*
X696879D01*
X696224Y-240038D01*
X695132Y-238872D01*
X693604Y-238289D01*
X692075Y-238580D01*
X690765Y-239455D01*
X689892Y-241497D01*
X689455Y-243247D01*
Y-244997D01*
X689892Y-246747D01*
X690984Y-248497D01*
X692294Y-249663D01*
X693822Y-249955D01*
X695350Y-249372D01*
X696879Y-247622D01*
G01X707392Y-247914D02*
X708484Y-249080D01*
X710012Y-249955D01*
X711322D01*
X712632Y-249372D01*
X713505Y-248497D01*
X713942Y-247331D01*
X713724Y-245580D01*
X712850Y-244705D01*
X708920Y-242955D01*
X708047Y-240913D01*
X708484Y-239455D01*
X709357Y-238580D01*
X710667Y-238289D01*
X711977Y-238580D01*
X713287Y-239455D01*
G01X728167Y-238289D02*
Y-249955D01*
G01Y-233622D02*
X727730Y-233330D01*
Y-232747D01*
X728167Y-232455D01*
X728604Y-232747D01*
Y-233330D01*
X728167Y-233622D01*
G01X742610Y-254330D02*
X744139Y-255497D01*
X745885Y-255788D01*
X747413Y-255497D01*
X748724Y-254039D01*
X749597Y-251997D01*
Y-238289D01*
G01Y-240622D02*
X748724Y-239455D01*
X747413Y-238580D01*
X745885Y-238289D01*
X744139Y-238872D01*
X743047Y-240038D01*
X742173Y-242080D01*
X741737Y-244122D01*
X741955Y-245872D01*
X742829Y-247914D01*
X744139Y-249372D01*
X745885Y-249955D01*
X747195Y-249663D01*
X748724Y-248497D01*
X749597Y-247331D01*
G01X759455Y-249955D02*
Y-238289D01*
G01Y-241205D02*
X760329Y-239747D01*
X761639Y-238580D01*
X763385Y-238289D01*
X764913Y-238580D01*
X766224Y-239747D01*
X766879Y-241788D01*
Y-249955D01*
G01X777392Y-242080D02*
X784379D01*
X783724Y-240038D01*
X782632Y-238872D01*
X781104Y-238289D01*
X779575Y-238580D01*
X778265Y-239455D01*
X777392Y-241497D01*
X776955Y-243247D01*
Y-244997D01*
X777392Y-246747D01*
X778484Y-248497D01*
X779794Y-249663D01*
X781322Y-249955D01*
X782850Y-249372D01*
X784379Y-247622D01*
G01X795110Y-249955D02*
Y-238289D01*
G01Y-240622D02*
X796202Y-239455D01*
X797294Y-238580D01*
X798822Y-238289D01*
X799913Y-238580D01*
X801224Y-239455D01*
G01X660367Y-277455D02*
X663423Y-294955D01*
X666917Y-277455D01*
X670410Y-294955D01*
X673467Y-277455D01*
G01X680050Y-294955D02*
Y-277455D01*
X685290D01*
X687037Y-278330D01*
X688347Y-280372D01*
X688784Y-282705D01*
X688347Y-285038D01*
X687255Y-286788D01*
X685290Y-287664D01*
X680050D01*
G01X697332Y-294955D02*
Y-277455D01*
G01X706502D02*
Y-294955D01*
G01Y-286205D02*
X697332D01*
G01X716579Y-289122D02*
X722255D01*
G01X732769Y-294955D02*
Y-277455D01*
X741065D01*
G01X738009Y-285913D02*
X732769D01*
G01X750050Y-277455D02*
Y-294955D01*
X758784D01*
G01X771917D02*
X770170Y-294663D01*
X768642Y-293497D01*
X767332Y-291747D01*
X766458Y-289705D01*
X766022Y-287372D01*
Y-285038D01*
X766458Y-282705D01*
X767332Y-280663D01*
X768642Y-278914D01*
X770170Y-277747D01*
X771917Y-277455D01*
X773663Y-277747D01*
X775192Y-278914D01*
X776502Y-280663D01*
X777376Y-282705D01*
X777812Y-285038D01*
Y-287372D01*
X777376Y-289705D01*
X776502Y-291747D01*
X775192Y-293497D01*
X773663Y-294663D01*
X771917Y-294955D01*
G01X785050D02*
Y-277455D01*
X790509D01*
X792255Y-278330D01*
X793347Y-279497D01*
X793784Y-281830D01*
X793347Y-284164D01*
X792037Y-285622D01*
X790509Y-286497D01*
X785050D01*
G01X790509D02*
X793784Y-294955D01*
G01X801458D02*
X806917Y-277455D01*
X812376Y-294955D01*
G01X810410Y-288830D02*
X803423D01*
G01X841867Y-294955D02*
Y-277455D01*
X839247Y-280955D01*
G01Y-294955D02*
X844487D01*
G01X859367D02*
Y-277455D01*
X856747Y-280955D01*
G01Y-294955D02*
X861987D01*
G01X872937Y-295538D02*
X880797Y-277455D01*
G01X894367Y-294955D02*
Y-277455D01*
X891747Y-280955D01*
G01Y-294955D02*
X896987D01*
G01X907719Y-287664D02*
X909247Y-285622D01*
X910557Y-284455D01*
X912304Y-283872D01*
X913832Y-284455D01*
X914924Y-285622D01*
X915797Y-287372D01*
X916015Y-289413D01*
X915797Y-291164D01*
X914924Y-292914D01*
X913613Y-294372D01*
X912085Y-294955D01*
X910339Y-294372D01*
X908810Y-292622D01*
X907937Y-289997D01*
X907719Y-287080D01*
X908155Y-283289D01*
X908810Y-281246D01*
X909902Y-279205D01*
X911430Y-277747D01*
X912959Y-277455D01*
X914487Y-278038D01*
X915579Y-279497D01*
G01X925437Y-295538D02*
X933297Y-277455D01*
G01X942719Y-280372D02*
X944029Y-278622D01*
X945557Y-277747D01*
X947304Y-277455D01*
X949487Y-278038D01*
X951015Y-279497D01*
X951452Y-281246D01*
X951234Y-282997D01*
X950360Y-284455D01*
X945994Y-287372D01*
X944029Y-289413D01*
X942719Y-292331D01*
X942282Y-294955D01*
X951452D01*
G01X964367Y-277455D02*
X962620Y-278038D01*
X961310Y-279497D01*
X960437Y-281246D01*
X959782Y-283580D01*
X959564Y-286205D01*
X959782Y-288830D01*
X960437Y-291164D01*
X961310Y-292914D01*
X962620Y-294372D01*
X964367Y-294955D01*
X966113Y-294372D01*
X967424Y-292914D01*
X968297Y-291164D01*
X968952Y-288830D01*
X969170Y-286205D01*
X968952Y-283580D01*
X968297Y-281246D01*
X967424Y-279497D01*
X966113Y-278038D01*
X964367Y-277455D01*
G01X981867Y-294955D02*
Y-277455D01*
X979247Y-280955D01*
G01Y-294955D02*
X984487D01*
G01X995219Y-287664D02*
X996747Y-285622D01*
X998057Y-284455D01*
X999804Y-283872D01*
X1001332Y-284455D01*
X1002424Y-285622D01*
X1003297Y-287372D01*
X1003515Y-289413D01*
X1003297Y-291164D01*
X1002424Y-292914D01*
X1001113Y-294372D01*
X999585Y-294955D01*
X997839Y-294372D01*
X996310Y-292622D01*
X995437Y-289997D01*
X995219Y-287080D01*
X995655Y-283289D01*
X996310Y-281246D01*
X997402Y-279205D01*
X998930Y-277747D01*
X1000459Y-277455D01*
X1001987Y-278038D01*
X1003079Y-279497D01*
G01X889564Y-249955D02*
Y-232455D01*
X893930D01*
X895677Y-233330D01*
X896987Y-234497D01*
X898079Y-236246D01*
X898952Y-238289D01*
X899170Y-241205D01*
X898952Y-244122D01*
X898079Y-246164D01*
X896987Y-247914D01*
X895677Y-249080D01*
X893930Y-249955D01*
X889564D01*
G01X915797D02*
Y-238289D01*
G01Y-240330D02*
X914924Y-239164D01*
X913613Y-238580D01*
X912085Y-238289D01*
X910557Y-238872D01*
X909247Y-240038D01*
X908373Y-241788D01*
X907937Y-244122D01*
X908373Y-246455D01*
X909247Y-248205D01*
X910557Y-249372D01*
X912085Y-249955D01*
X913613Y-249663D01*
X914924Y-248789D01*
X915797Y-247622D01*
G01X929367Y-232455D02*
Y-249955D01*
G01X926310Y-238289D02*
X932424D01*
G01X943592Y-242080D02*
X950579D01*
X949924Y-240038D01*
X948832Y-238872D01*
X947304Y-238289D01*
X945775Y-238580D01*
X944465Y-239455D01*
X943592Y-241497D01*
X943155Y-243247D01*
Y-244997D01*
X943592Y-246747D01*
X944684Y-248497D01*
X945994Y-249663D01*
X947522Y-249955D01*
X949050Y-249372D01*
X950579Y-247622D01*
G54D14*
X8858Y629693D03*
Y626544D03*
Y623394D03*
Y620245D03*
Y617095D03*
Y613945D03*
Y610796D03*
Y607646D03*
Y604496D03*
Y601347D03*
Y598197D03*
Y702134D03*
Y698985D03*
Y695835D03*
Y692685D03*
Y689536D03*
Y686386D03*
Y683237D03*
Y680087D03*
Y676937D03*
Y673788D03*
Y670638D03*
Y667489D03*
Y664339D03*
Y661189D03*
Y658040D03*
Y654890D03*
Y651741D03*
Y648591D03*
Y645441D03*
Y642292D03*
Y639142D03*
Y635993D03*
Y632843D03*
Y774575D03*
Y771426D03*
Y768276D03*
Y765126D03*
Y761977D03*
Y758827D03*
Y755678D03*
Y752528D03*
Y749378D03*
Y733630D03*
Y730481D03*
Y727331D03*
Y724182D03*
Y721032D03*
Y717882D03*
Y714733D03*
Y711583D03*
Y708433D03*
Y705284D03*
Y847016D03*
Y843867D03*
Y840717D03*
Y837567D03*
Y834418D03*
Y831268D03*
Y828119D03*
Y824969D03*
Y821819D03*
Y818670D03*
Y815520D03*
Y812371D03*
Y809221D03*
Y806071D03*
Y802922D03*
Y799772D03*
Y796622D03*
Y793473D03*
Y790323D03*
Y787174D03*
Y784024D03*
Y780874D03*
Y777725D03*
Y919457D03*
Y916308D03*
Y913158D03*
Y910008D03*
Y906859D03*
Y903709D03*
Y900559D03*
Y897410D03*
Y894260D03*
Y891111D03*
Y887961D03*
Y884811D03*
Y881662D03*
Y878512D03*
Y875363D03*
Y872213D03*
Y869063D03*
Y865914D03*
Y862764D03*
Y859615D03*
Y856465D03*
Y853315D03*
Y850166D03*
Y922607D03*
Y1138355D03*
Y1135205D03*
Y1132056D03*
Y1128906D03*
Y1125756D03*
Y1122607D03*
Y1119457D03*
Y1116308D03*
Y1113158D03*
Y1110008D03*
Y1106859D03*
Y1103709D03*
Y1100559D03*
Y1097410D03*
Y1094260D03*
Y1210796D03*
Y1207646D03*
Y1204496D03*
Y1201347D03*
Y1198197D03*
Y1195048D03*
Y1191898D03*
Y1188748D03*
Y1185599D03*
Y1182449D03*
Y1179300D03*
Y1176150D03*
Y1173000D03*
Y1169851D03*
Y1166701D03*
Y1163552D03*
Y1160402D03*
Y1157252D03*
Y1154103D03*
Y1150953D03*
Y1147804D03*
Y1144654D03*
Y1141504D03*
Y1283237D03*
Y1280087D03*
Y1276937D03*
Y1273788D03*
Y1270638D03*
Y1267489D03*
Y1264339D03*
Y1261189D03*
Y1258040D03*
Y1254890D03*
Y1251741D03*
Y1248591D03*
Y1245441D03*
Y1229693D03*
Y1226544D03*
Y1223394D03*
Y1220245D03*
Y1217095D03*
Y1213945D03*
Y1355678D03*
Y1352528D03*
Y1349378D03*
Y1346229D03*
Y1343079D03*
Y1339930D03*
Y1336780D03*
Y1333630D03*
Y1330481D03*
Y1327331D03*
Y1324182D03*
Y1321032D03*
Y1317882D03*
Y1314733D03*
Y1311583D03*
Y1308434D03*
Y1305284D03*
Y1302134D03*
Y1298985D03*
Y1295835D03*
Y1292685D03*
Y1289536D03*
Y1286386D03*
Y1418670D03*
Y1415520D03*
Y1412371D03*
Y1409221D03*
Y1406071D03*
Y1402922D03*
Y1399772D03*
Y1396622D03*
Y1393473D03*
Y1390323D03*
Y1387174D03*
Y1384024D03*
Y1380874D03*
Y1377725D03*
Y1374575D03*
Y1371426D03*
Y1368276D03*
Y1365126D03*
Y1361977D03*
Y1358827D03*
Y1574574D03*
Y1571425D03*
Y1568275D03*
Y1565126D03*
Y1561976D03*
Y1558826D03*
Y1555677D03*
Y1552527D03*
Y1549378D03*
Y1546228D03*
Y1543078D03*
Y1539929D03*
Y1536779D03*
Y1533630D03*
Y1530480D03*
Y1527330D03*
Y1524181D03*
Y1521031D03*
Y1517881D03*
Y1514732D03*
Y1511582D03*
Y1647015D03*
Y1643866D03*
Y1640716D03*
Y1637567D03*
Y1634417D03*
Y1631267D03*
Y1628118D03*
Y1624968D03*
Y1621818D03*
Y1618669D03*
Y1615519D03*
Y1612370D03*
Y1609220D03*
Y1606070D03*
Y1602921D03*
Y1599771D03*
Y1596622D03*
Y1593472D03*
Y1590322D03*
Y1587173D03*
Y1584023D03*
Y1580874D03*
Y1577724D03*
Y1719456D03*
Y1716307D03*
Y1713157D03*
Y1710007D03*
Y1706858D03*
Y1703708D03*
Y1700559D03*
Y1697409D03*
Y1694259D03*
Y1691110D03*
Y1687960D03*
Y1684811D03*
Y1681661D03*
Y1678511D03*
Y1675362D03*
Y1672212D03*
Y1669063D03*
Y1665913D03*
Y1662763D03*
Y1791897D03*
Y1788748D03*
Y1785598D03*
Y1782448D03*
Y1779299D03*
Y1776149D03*
Y1773000D03*
Y1769850D03*
Y1766700D03*
Y1763551D03*
Y1760401D03*
Y1757252D03*
Y1754102D03*
Y1750952D03*
Y1747803D03*
Y1744653D03*
Y1741504D03*
Y1738354D03*
Y1735204D03*
Y1732055D03*
Y1728905D03*
Y1725756D03*
Y1722606D03*
Y1835992D03*
Y1832842D03*
Y1829693D03*
Y1826543D03*
Y1823393D03*
Y1820244D03*
Y1817094D03*
Y1813944D03*
Y1810795D03*
Y1807645D03*
Y1804496D03*
Y1801346D03*
Y1798196D03*
Y1795047D03*
G54D24*
G01X114579Y137775D02*
Y196219D01*
X107611Y203187D01*
Y211470D01*
X101448Y217633D01*
X96306D01*
X94526Y219413D01*
Y255574D01*
X64400Y285700D01*
Y324517D01*
X30100Y358817D01*
Y731900D01*
X27400Y734600D01*
X23262D01*
X17831Y729169D01*
X14731D01*
X13419Y730481D01*
X7358D01*
G01X213244Y23725D02*
X208019Y18500D01*
X161100D01*
X143600Y36000D01*
Y43300D01*
X136900Y50000D01*
X113800D01*
X111050Y47250D01*
X90150D01*
X87500Y49900D01*
X66800D01*
X57200Y59500D01*
Y198600D01*
X92331Y233731D01*
Y254692D01*
X62225Y284798D01*
Y323168D01*
X24675Y360718D01*
Y594825D01*
X18153Y601347D01*
X7358D01*
G01X73900Y269500D02*
X60050Y283350D01*
Y322267D01*
X22500Y359817D01*
Y588500D01*
X12803Y598197D01*
X7358D01*
G01X890469Y164804D02*
Y162469D01*
X879400Y151400D01*
X807024D01*
X785099Y173325D01*
X150099D01*
X116825Y206599D01*
Y217625D01*
X101051Y233399D01*
Y258873D01*
X73125Y286799D01*
Y322699D01*
X37000Y358824D01*
Y762000D01*
G01X7358Y774575D02*
X14250D01*
X15000Y773825D01*
X18325D01*
X23500Y779000D01*
X28000D01*
X34450Y772550D01*
Y358105D01*
X70950Y321605D01*
Y285898D01*
X98876Y257972D01*
Y232498D01*
X114650Y216724D01*
Y205698D01*
X149198Y171150D01*
X784198D01*
X806473Y148875D01*
X864975D01*
G01X27699Y737535D02*
X24535D01*
X17662Y730662D01*
X15739D01*
X14662Y731739D01*
Y732000D01*
X13032Y733630D01*
X7358D01*
G01Y780874D02*
X15874D01*
X18500Y783500D01*
X29652D01*
X39500Y773652D01*
Y359400D01*
X75300Y323600D01*
Y287700D01*
X103271Y259729D01*
Y234750D01*
X119000Y219021D01*
Y207500D01*
X151000Y175500D01*
X786000D01*
X807800Y153700D01*
X878200D01*
X888000Y163500D01*
Y166500D01*
X890000Y168500D01*
X900000D01*
X925800Y194300D01*
Y243700D01*
X922300Y247200D01*
X906991D01*
X906691Y247500D01*
X900824D01*
X898300Y250024D01*
Y256400D01*
X907500Y265600D01*
Y356500D01*
X890500Y373500D01*
X812031D01*
X807756Y377775D01*
G01X37000Y762000D02*
Y773076D01*
X29401Y780675D01*
X22675D01*
X17787Y775787D01*
X15697D01*
X13759Y777725D01*
X7358D01*
G01Y922607D02*
X26393D01*
X41000Y908000D01*
G01X34872Y890906D02*
Y894522D01*
X27894Y901500D01*
X23567D01*
X22344Y900277D01*
Y899556D01*
X17048Y894260D01*
X7358D01*
G01Y891111D02*
X14500D01*
X15389Y892000D01*
X19241D01*
X20766Y890475D01*
X29521D01*
X46321Y873675D01*
Y827414D01*
X80215Y793520D01*
Y787900D01*
G01X43387Y803500D02*
Y872711D01*
X27298Y888800D01*
X19800D01*
X18000Y887000D01*
X15461D01*
X14500Y887961D01*
X7358D01*
G01X40087Y788400D02*
Y866913D01*
X30000Y877000D01*
X24401D01*
X22300Y879101D01*
Y879600D01*
X17089Y884811D01*
X7358D01*
G01X42286Y1089500D02*
X17500D01*
X12740Y1094260D01*
X7358D01*
G01X32335Y1122002D02*
X22650D01*
X18896Y1125756D01*
X7358D01*
G01Y1128906D02*
X21711D01*
X25423Y1125194D01*
X32176D01*
X75500Y1081870D01*
Y1053000D01*
X79000Y1049500D01*
Y1025103D01*
X65744Y1011847D01*
X63423D01*
X58675Y1007099D01*
Y937825D01*
X67500Y929000D01*
X73000D01*
X74000Y928000D01*
Y919500D01*
X52800Y898300D01*
Y825700D01*
X73000Y805500D01*
X80100D01*
G01X67090Y1070360D02*
X43950Y1093500D01*
X22300D01*
X18390Y1097410D01*
X7358D01*
G01X81175Y1066404D02*
Y1079271D01*
X33077Y1127369D01*
X24910D01*
X21779Y1130500D01*
X15000D01*
X13444Y1132056D01*
X7358D01*
G01X37396Y1130912D02*
X41916D01*
X125800Y1047028D01*
Y988700D01*
X148000Y966500D01*
G01X7358Y1135205D02*
X15305D01*
X15700Y1135600D01*
X18507D01*
X24563Y1129544D01*
X34053D01*
X106100Y1057497D01*
Y1030000D01*
G01X33971Y1131741D02*
X35400Y1133170D01*
X42734D01*
X128300Y1047604D01*
Y991000D01*
X141250Y978050D01*
G01X132000Y1042000D02*
Y1051241D01*
X71241Y1112000D01*
X67000D01*
X36425Y1142575D01*
Y1231012D01*
X32959Y1234478D01*
G01X36000Y1236000D02*
X38600Y1233400D01*
Y1153700D01*
X112700Y1079600D01*
G01X33201Y1230674D02*
X23362D01*
X18046Y1225358D01*
X15357D01*
X14171Y1226544D01*
X7358D01*
G01Y1229693D02*
X12794D01*
X14596Y1227891D01*
Y1227805D01*
X15739Y1226662D01*
X17662D01*
X29900Y1238900D01*
X45550D01*
X51944Y1232506D01*
G01X71000Y1335488D02*
X71012D01*
X74500Y1332000D01*
Y1316297D01*
X70350Y1312147D01*
X61578D01*
X51213Y1301782D01*
X33699D01*
G01X7358Y1308434D02*
X16166D01*
X19479Y1305121D01*
X26500D01*
G01X7358Y1311583D02*
X13183D01*
X15200Y1313600D01*
X17400D01*
X22300Y1308700D01*
X28000D01*
X34125Y1314825D01*
X65525D01*
X69900Y1319200D01*
Y1331100D01*
X65000Y1336000D01*
G01X7358Y1314733D02*
X14033D01*
X14700Y1315400D01*
X17262D01*
X22787Y1309875D01*
X26099D01*
X33624Y1317400D01*
X50100D01*
G01X69365Y1474719D02*
X66618Y1471972D01*
Y1460194D01*
X25094Y1418670D01*
X7358D01*
G01X27000Y1417500D02*
X70000Y1460500D01*
X99500D01*
X162500Y1397500D01*
Y1380500D01*
G01X94642Y1456100D02*
X85456D01*
X83231Y1458325D01*
X70901D01*
X32500Y1419924D01*
Y1417600D01*
G01X46845Y1514264D02*
X41977D01*
X40132Y1516109D01*
Y1522350D01*
X38382Y1524100D01*
X32100D01*
X28000Y1520000D01*
X22000D01*
X17819Y1524181D01*
X7358D01*
G01X136500Y1733000D02*
X126000D01*
X124476Y1734524D01*
X101372D01*
X98748Y1731900D01*
X86376D01*
X80776Y1726300D01*
X55724D01*
X42021Y1712597D01*
X34252D01*
X31742Y1710087D01*
Y1669180D01*
X28523Y1665961D01*
Y1650311D01*
X33734Y1645100D01*
Y1592360D01*
X42919Y1583175D01*
G01X55738Y1578587D02*
X52951Y1575800D01*
X17800D01*
X15876Y1577724D01*
X7358D01*
G01Y1580874D02*
X14826D01*
X15800Y1579900D01*
X17600D01*
X20000Y1577500D01*
X27123D01*
X27598Y1577975D01*
X50926D01*
X58777Y1585826D01*
G01X7358Y1584023D02*
X15023D01*
X16000Y1585000D01*
X17500D01*
X23225Y1579275D01*
X25848D01*
X27336Y1580763D01*
X46578D01*
X49555Y1583740D01*
G01X35900Y1706000D02*
X44273D01*
X60220Y1721947D01*
X82523D01*
X82526Y1721950D01*
X82578D01*
X85803Y1725175D01*
X98175D01*
X103174Y1730174D01*
X114726D01*
X117400Y1727500D01*
X122000D01*
G01X7358Y1706858D02*
X14658D01*
X15600Y1707800D01*
X17800D01*
X19500Y1709500D01*
X21720D01*
X47582Y1735362D01*
X75462D01*
X82950Y1742850D01*
X97394D01*
X97768Y1743224D01*
X133824D01*
X147200Y1756600D01*
G01X34224Y1709000D02*
X42093D01*
X45402Y1712309D01*
G01X157900Y1770500D02*
Y1762295D01*
X136654Y1741049D01*
X98669D01*
X98295Y1740675D01*
X83851D01*
X76363Y1733187D01*
X48561D01*
X22874Y1707500D01*
X20800D01*
X18150Y1704850D01*
X16050D01*
X14908Y1703708D01*
X7358D01*
G01X38000Y1715000D02*
X39500D01*
X45150Y1720650D01*
G01X83600Y1736600D02*
X78012Y1731012D01*
X49591D01*
X24079Y1705500D01*
X23000D01*
X18059Y1700559D01*
X7358D01*
G01X326167Y811099D02*
X324860Y812406D01*
X317087D01*
X313000Y808319D01*
Y805076D01*
X317476Y800600D01*
X342795D01*
X351720Y791675D01*
X439275D01*
X466600Y819000D01*
Y1762100D01*
X455900Y1772800D01*
X353700D01*
X277588Y1848912D01*
X170612D01*
X164699Y1854825D01*
X141994D01*
X127281Y1869538D01*
X77038D01*
X65051Y1857551D01*
Y1798907D01*
X49969Y1783825D01*
X30301D01*
X23375Y1776899D01*
Y1773875D01*
X19900Y1770400D01*
X14700D01*
X14150Y1769850D01*
X7358D01*
G01X326167Y814902D02*
X325846Y814581D01*
X316186D01*
X310825Y809220D01*
Y804175D01*
X316575Y798425D01*
X341894D01*
X350819Y789500D01*
X440176D01*
X468775Y818099D01*
Y1763001D01*
X456801Y1774975D01*
X354601D01*
X278489Y1851087D01*
X171513D01*
X165600Y1857000D01*
X142895D01*
X128182Y1871713D01*
X76137D01*
X62876Y1858452D01*
Y1799808D01*
X49068Y1786000D01*
X29400D01*
X21200Y1777800D01*
Y1774776D01*
X18999Y1772575D01*
X14411D01*
X13986Y1773000D01*
X7358D01*
G01X53200Y1865800D02*
Y1864756D01*
X52000Y1863556D01*
Y1863555D01*
X51837Y1863392D01*
Y1805952D01*
X51838Y1805951D01*
Y1804151D01*
X44737Y1797050D01*
X27084D01*
X23034Y1793000D01*
X15603D01*
X14500Y1791897D01*
X7358D01*
G01Y1788748D02*
X14252D01*
X14700Y1788300D01*
X20509D01*
X27084Y1794875D01*
X45638D01*
X54175Y1803412D01*
Y1862654D01*
X55538Y1864017D01*
Y1877038D01*
X54175Y1878401D01*
Y1888775D01*
X57719Y1892319D01*
X79508D01*
X125489Y1938300D01*
X129348D01*
X139548Y1948500D01*
X725652D01*
X866850Y1807302D01*
Y1786302D01*
X901702Y1751450D01*
X930202D01*
X942350Y1739302D01*
Y1686350D01*
X931000Y1675000D01*
Y1671500D01*
G01X7358Y1782448D02*
X14052D01*
X14700Y1781800D01*
X18675D01*
X27400Y1790525D01*
X47440D01*
X58525Y1801610D01*
Y1860851D01*
X59798Y1862124D01*
X59799D01*
X59888Y1862213D01*
Y1878840D01*
X58525Y1880203D01*
Y1886825D01*
X59669Y1887969D01*
X81310D01*
X126941Y1933600D01*
X130800D01*
X141200Y1944000D01*
X724000D01*
X862500Y1805500D01*
Y1784500D01*
X899900Y1747100D01*
X928400D01*
X937000Y1738500D01*
Y1692000D01*
X930000Y1685000D01*
G01X939500Y1698000D02*
Y1739076D01*
X929301Y1749275D01*
X900801D01*
X864675Y1785401D01*
Y1806401D01*
X724901Y1946175D01*
X140299D01*
X130124Y1936000D01*
X126265D01*
X80409Y1890144D01*
X58744D01*
X56350Y1887750D01*
Y1879302D01*
X57713Y1877939D01*
Y1863115D01*
X57624Y1863026D01*
X57623D01*
X56350Y1861753D01*
Y1802511D01*
X46539Y1792700D01*
X27084D01*
X20509Y1786125D01*
X15527D01*
X15000Y1785598D01*
X7358D01*
G01X60897Y1885848D02*
X60700Y1885651D01*
Y1881104D01*
X62063Y1879741D01*
Y1861312D01*
X60701Y1859950D01*
Y1800709D01*
X59430Y1799438D01*
X59429D01*
X48341Y1788350D01*
X28301D01*
X19250Y1779299D01*
X7358D01*
G01Y1798196D02*
X22979D01*
X26183Y1801400D01*
X42935D01*
X47487Y1805952D01*
Y1870474D01*
X45825Y1872136D01*
Y1878402D01*
X49495Y1882072D01*
Y1890391D01*
X53985Y1894881D01*
X63579D01*
G01X7358Y1795047D02*
X22906D01*
X27084Y1799225D01*
X43836D01*
X49662Y1805051D01*
Y1868200D01*
X50100Y1868638D01*
Y1872800D01*
G01X901600Y249800D02*
X923400D01*
X928100Y245100D01*
Y188700D01*
X886100Y146700D01*
X805572D01*
X783297Y168975D01*
X148297D01*
X112075Y205197D01*
Y216223D01*
X96701Y231597D01*
Y257071D01*
X68775Y284997D01*
Y293791D01*
X66610Y295956D01*
G01X80300Y234465D02*
X88596D01*
X90100Y235969D01*
Y253300D01*
X73900Y269500D01*
G01X105750Y217750D02*
X109900Y213600D01*
Y204296D01*
X147396Y166800D01*
X194300D01*
X196200Y164900D01*
X201500D01*
X203400Y166800D01*
X292445D01*
X292600Y166955D01*
G01X97400Y220200D02*
X103300D01*
X105750Y217750D01*
G01X52066Y370649D02*
X62121Y380704D01*
X78675D01*
G01X49500Y771000D02*
X89150Y731350D01*
X150302D01*
X167136Y714516D01*
Y661064D01*
X173000Y655200D01*
G01X157750Y544750D02*
X153500Y549000D01*
Y581692D01*
X143700Y591492D01*
Y624200D01*
X140900Y627000D01*
Y647800D01*
X164749Y671649D01*
Y713827D01*
X149401Y729175D01*
X86901D01*
X45632Y770444D01*
Y782418D01*
X43387Y784663D01*
Y803500D01*
G01X150850Y574350D02*
Y580925D01*
X141525Y590250D01*
Y608050D01*
X133000Y616575D01*
Y642976D01*
X162574Y672550D01*
Y712926D01*
X148500Y727000D01*
X86000D01*
X43457Y769543D01*
Y781041D01*
X40087Y784411D01*
Y788400D01*
G01X143800Y807400D02*
X141900Y805500D01*
X80100D01*
G01X80215Y777137D02*
Y787900D01*
G01X41000Y908000D02*
X47500Y901500D01*
G01X56000Y967000D02*
Y937000D01*
X65500Y927500D01*
G01X74000Y1047500D02*
X76750Y1044750D01*
Y1025929D01*
X65537Y1014716D01*
X63216D01*
X56000Y1007500D01*
Y967000D01*
G01X42286Y1085500D02*
X48798D01*
X71000Y1063298D01*
Y1047000D01*
X74300Y1043700D01*
Y1029876D01*
X53400Y1008976D01*
Y935500D01*
X64200Y924700D01*
X70200D01*
X71000Y925500D01*
G01X41608Y1125065D02*
X120500Y1046173D01*
Y984500D01*
X154500Y950500D01*
X156900D01*
X157200Y950800D01*
G01X39959Y1128308D02*
X41444D01*
X122800Y1046952D01*
Y986700D01*
X155300Y954200D01*
X155900D01*
G01X81689Y1049400D02*
X81175Y1049914D01*
Y1066404D01*
G01X106100Y1030000D02*
X118200Y1017900D01*
Y982100D01*
X142066Y958234D01*
G01X40097Y1142513D02*
X45610Y1137000D01*
X51000D01*
X124500Y1063500D01*
X169900D01*
X173000Y1060400D01*
G01X51944Y1232506D02*
X85300Y1199150D01*
Y1182000D01*
G01X79390Y1327082D02*
Y1284587D01*
X72500Y1277697D01*
G01X73000Y1455100D02*
X74996Y1453104D01*
X82547D01*
X86384Y1449267D01*
Y1437015D01*
X59500Y1410131D01*
Y1345000D01*
X66000Y1338500D01*
X73500D01*
X79390Y1332610D01*
Y1327082D01*
G01X80300Y1451000D02*
X80407Y1450893D01*
X81578D01*
X84097Y1448374D01*
Y1438028D01*
X57000Y1410931D01*
Y1344000D01*
X65000Y1336000D01*
G01X50100Y1317400D02*
X58500D01*
X58900Y1317000D01*
G01X94642Y1456100D02*
X100824D01*
X158875Y1398049D01*
Y1376100D01*
G01X82005Y1540500D02*
X82825Y1539680D01*
Y1534599D01*
X89911Y1527513D01*
X127313D01*
X140635Y1540835D01*
X185484D01*
X220400Y1505919D01*
Y1349476D01*
X212325Y1341401D01*
Y957701D01*
X115825Y861201D01*
Y841899D01*
X120499Y837225D01*
X159199D01*
X175225Y821199D01*
Y799199D01*
X205825Y768599D01*
Y594101D01*
X178325Y566601D01*
Y532399D01*
X182624Y528100D01*
X187853D01*
X188854Y527099D01*
G01X276402Y1726146D02*
X275588Y1726960D01*
Y1739588D01*
X263801Y1751375D01*
X212194D01*
X167494Y1706675D01*
X139099D01*
X100825Y1668401D01*
Y1635901D01*
X83125Y1618201D01*
Y1541620D01*
X82005Y1540500D01*
G01X85808D02*
X85000Y1539692D01*
Y1535500D01*
X90812Y1529688D01*
X126412D01*
X139734Y1543010D01*
X186385D01*
X222575Y1506820D01*
Y1348575D01*
X214500Y1340500D01*
Y956800D01*
X118000Y860300D01*
Y842800D01*
X121400Y839400D01*
X160100D01*
X177400Y822100D01*
Y800100D01*
X208000Y769500D01*
Y593200D01*
X180500Y565700D01*
Y533300D01*
X183525Y530275D01*
X188227D01*
X188854Y530902D01*
G01X272599Y1726146D02*
X273413Y1726960D01*
Y1738687D01*
X262900Y1749200D01*
X213095D01*
X168395Y1704500D01*
X140000D01*
X103000Y1667500D01*
Y1635000D01*
X85300Y1617300D01*
Y1541008D01*
X85808Y1540500D01*
G01X64525Y1591016D02*
Y1587374D01*
X55738Y1578587D01*
G01X58777Y1585826D02*
X60037Y1587086D01*
Y1700537D01*
X66400Y1706900D01*
G01X49555Y1583740D02*
X57862Y1592047D01*
Y1705162D01*
X72472Y1719772D01*
X83424D01*
X83427Y1719775D01*
X83479D01*
X86704Y1723000D01*
X100915D01*
X103877Y1720038D01*
X112363D01*
X116425Y1724100D01*
X140300D01*
G01X45402Y1712309D02*
X57215Y1724122D01*
X81622D01*
X81625Y1724125D01*
X81677D01*
X84902Y1727350D01*
X97274D01*
X102273Y1732349D01*
X122227D01*
X124751Y1729825D01*
X140825D01*
G01X45150Y1720650D02*
X53337Y1728837D01*
X80237D01*
X85504Y1734104D01*
X97876D01*
X100471Y1736699D01*
X139501D01*
X144500Y1731700D01*
Y1720500D01*
X144400Y1720400D01*
G01X98000Y1848800D02*
X97977Y1848777D01*
Y1833154D01*
X95900Y1831077D01*
Y1801000D01*
X78700Y1783800D01*
X68500D01*
X55500Y1770800D01*
Y1763000D01*
G01X67000Y1738000D02*
X60000D01*
X55500Y1742500D01*
Y1763000D01*
G01X83600Y1736600D02*
X85500Y1738500D01*
X99196D01*
X99570Y1738874D01*
X140426D01*
X147300Y1732000D01*
Y1724600D01*
X147200Y1724500D01*
Y1724400D01*
G01X53200Y1865800D02*
Y1876300D01*
X52000Y1877500D01*
G01X85000Y1817100D02*
Y1815000D01*
X74100Y1804100D01*
Y1796200D01*
G01X67800Y1855200D02*
X70038Y1852962D01*
X84205D01*
X95802Y1841365D01*
Y1834055D01*
X93625Y1831878D01*
Y1802200D01*
G01X1008244Y1636102D02*
X999898D01*
X997500Y1638500D01*
X946000D01*
X936000Y1648500D01*
Y1676000D01*
X944825Y1684825D01*
Y1740328D01*
X931228Y1753925D01*
X902728D01*
X869325Y1787328D01*
Y1808328D01*
X726953Y1950700D01*
X138672D01*
X128715Y1940743D01*
X124856D01*
X78994Y1894881D01*
X63579D01*
G01X70650Y1897792D02*
X53772D01*
X46868Y1890888D01*
Y1887765D01*
G01X70650Y1897792D02*
X78369D01*
X133577Y1953000D01*
X728189D01*
X871825Y1809364D01*
Y1788364D01*
X904089Y1756100D01*
X932589D01*
X947325Y1741364D01*
Y1683825D01*
X938500Y1675000D01*
Y1651000D01*
X940573Y1648927D01*
X996573D01*
X999398Y1646102D01*
X1008244D01*
G01X48000Y1877500D02*
X50100Y1875400D01*
Y1872800D01*
G01X143600Y252100D02*
X170200D01*
X172900Y249400D01*
G01X126221Y861250D02*
Y859756D01*
X125546Y859081D01*
X122686D01*
X120513Y856908D01*
Y848511D01*
X123699Y845325D01*
X163599D01*
X245700Y763224D01*
Y665800D01*
X287000Y624500D01*
Y616570D01*
X286130Y615700D01*
G01X183344Y808200D02*
X185200D01*
X185925Y807475D01*
Y799880D01*
X239513Y746292D01*
Y613411D01*
X261099Y591825D01*
X268905D01*
X269800Y590930D01*
G01X126221Y853750D02*
Y856231D01*
X125546Y856906D01*
X123587D01*
X122688Y856007D01*
Y849412D01*
X124600Y847500D01*
X164500D01*
X247875Y764125D01*
Y666701D01*
X289175Y625401D01*
Y616458D01*
X289933Y615700D01*
G01X157000Y957500D02*
X148000Y966500D01*
G01X198900Y965477D02*
X161523D01*
X132000Y995000D01*
Y1042000D01*
G01X142066Y958234D02*
X153600Y946700D01*
X160600D01*
X161200Y946100D01*
G01X161700Y950800D02*
Y957600D01*
X141250Y978050D01*
G01X112700Y1079600D02*
X125300Y1067000D01*
X139300D01*
G01X162500Y1380500D02*
Y1359500D01*
X158250Y1355250D01*
Y1348054D01*
X154709Y1344513D01*
G01X173100Y1466300D02*
X170648Y1468752D01*
X148095D01*
G01X282030Y1451400D02*
X282900Y1452270D01*
Y1456524D01*
X279724Y1459700D01*
X262224D01*
X245600Y1476324D01*
Y1505219D01*
X203319Y1547500D01*
X140300D01*
X131925Y1539125D01*
X118425D01*
X117387Y1538087D01*
Y1536250D01*
G01X285833Y1451400D02*
X285075Y1452158D01*
Y1457425D01*
X280625Y1461875D01*
X263125D01*
X247775Y1477225D01*
Y1506120D01*
X204220Y1549675D01*
X139399D01*
X131024Y1541300D01*
X118500D01*
X117387Y1542413D01*
Y1543750D01*
G01X122844Y1672400D02*
X124700D01*
X125225Y1671875D01*
Y1666275D01*
X300312Y1491188D01*
Y1466493D01*
X294625Y1460806D01*
Y1452295D01*
X293830Y1451500D01*
G01X130344Y1672400D02*
X127863D01*
X127400Y1671937D01*
Y1667176D01*
X302487Y1492089D01*
Y1465592D01*
X296800Y1459905D01*
Y1452333D01*
X297633Y1451500D01*
G01X137000Y1727500D02*
X122000D01*
G01X151452Y1810000D02*
Y1760852D01*
X147200Y1756600D01*
G01X157898Y1780145D02*
Y1777954D01*
X157900Y1777952D01*
Y1770500D01*
G01X173500Y1871700D02*
X169230Y1875970D01*
X113500D01*
G01X188854Y527099D02*
X189480Y527725D01*
X192275D01*
X195000Y525000D01*
Y373500D01*
X268700Y299800D01*
X424856D01*
X427500Y297156D01*
G01X188854Y530902D02*
X189856Y529900D01*
X193176D01*
X197175Y525901D01*
Y374401D01*
X269601Y301975D01*
X424819D01*
X427500Y304656D01*
G01X270000Y567130D02*
X269105Y568025D01*
X255920D01*
X240987Y553092D01*
Y382735D01*
X241662Y382060D01*
X243156D01*
G01X270000Y570933D02*
X269267Y570200D01*
X255019D01*
X238812Y553993D01*
Y382735D01*
X238137Y382060D01*
X235656D01*
G01X228156Y438500D02*
X225675D01*
X225200Y438975D01*
Y552805D01*
X252320Y579925D01*
X269105D01*
X270000Y579030D01*
G01X220656Y438500D02*
X222625D01*
X223025Y438900D01*
Y553706D01*
X251419Y582100D01*
X269267D01*
X270000Y582833D01*
G01X190844Y808200D02*
X189000D01*
X188100Y807300D01*
Y800781D01*
X241688Y747193D01*
Y614312D01*
X262000Y594000D01*
X269067D01*
X269800Y594733D01*
G01X208875Y957200D02*
Y960370D01*
X209968Y961463D01*
Y1056332D01*
X196000Y1070300D01*
G01X270100Y1425697D02*
X269597Y1426200D01*
X261700D01*
X233900Y1398400D01*
Y1266800D01*
X237200Y1263500D01*
X242025D01*
X242700Y1264175D01*
Y1266656D01*
G01X270100Y1429500D02*
X268975Y1428375D01*
X260799D01*
X231725Y1399301D01*
Y1265899D01*
X236299Y1261325D01*
X242025D01*
X242700Y1260650D01*
Y1259156D01*
G01X270000Y1413530D02*
X269205Y1414325D01*
X265720D01*
X256475Y1405080D01*
Y1382701D01*
X274175Y1365001D01*
Y1183735D01*
X274850Y1183060D01*
X276344D01*
G01X270000Y1417333D02*
X269167Y1416500D01*
X264819D01*
X254300Y1405981D01*
Y1381800D01*
X272000Y1364100D01*
Y1183735D01*
X271325Y1183060D01*
X268844D01*
G01X232344Y1740000D02*
X234200D01*
X235100Y1739100D01*
Y1570700D01*
X306525Y1499275D01*
Y1451995D01*
X305830Y1451300D01*
G01X239844Y1740000D02*
X238300D01*
X237275Y1738975D01*
Y1571601D01*
X308700Y1500176D01*
Y1452233D01*
X309633Y1451300D01*
G01X248500Y1713005D02*
X249295Y1713800D01*
X255224D01*
X263712Y1705312D01*
X313007D01*
X320800Y1697519D01*
Y1695084D01*
X318156Y1692440D01*
G01X325656D02*
X322975Y1695121D01*
Y1698420D01*
X313908Y1707487D01*
X264613D01*
X256125Y1715975D01*
X249333D01*
X248500Y1716808D01*
G01X431156Y1669000D02*
X433637D01*
X434312Y1669675D01*
Y1723688D01*
X427900Y1730100D01*
X399275D01*
X391137Y1738238D01*
X362463D01*
X355661Y1731436D01*
X306761D01*
X287838Y1712513D01*
X264789D01*
X264152Y1713150D01*
X264153D01*
X252506Y1724797D01*
Y1737759D01*
X251692Y1738573D01*
G01X255495D02*
X254681Y1737759D01*
Y1725698D01*
X265691Y1714688D01*
X286937D01*
X305860Y1733611D01*
X354760D01*
X361562Y1740413D01*
X392038D01*
X400176Y1732275D01*
X428801D01*
X436487Y1724589D01*
Y1670301D01*
X437788Y1669000D01*
X438656D01*
G01X343668Y1750741D02*
X338275Y1745348D01*
X285352D01*
X277150Y1753550D01*
X233200D01*
X224875Y1761875D01*
Y1768100D01*
G01X318656Y391440D02*
X321137D01*
X321812Y392115D01*
Y396100D01*
G01D02*
Y397788D01*
X324125Y400101D01*
Y431499D01*
X315400Y440224D01*
Y490581D01*
X356812Y531993D01*
Y566507D01*
X349919Y573400D01*
X340233D01*
X339500Y572667D01*
G01X321812Y396100D02*
X320700D01*
G01X317575Y469800D02*
Y441125D01*
X326300Y432400D01*
Y399200D01*
X323987Y396887D01*
Y392115D01*
X324662Y391440D01*
X326156D01*
G01X339500Y576470D02*
X340395Y575575D01*
X350820D01*
X358987Y567408D01*
Y531092D01*
X317575Y489680D01*
Y469800D01*
G01D02*
X318700D01*
G01X296470Y555500D02*
X296149Y555179D01*
Y548573D01*
X291501Y543925D01*
X284538D01*
X284000Y543387D01*
Y541344D01*
G01Y548844D02*
Y546627D01*
X284527Y546100D01*
X290600D01*
X293974Y549474D01*
Y554193D01*
X292667Y555500D01*
G01X332500Y605000D02*
X302000D01*
X298438Y608562D01*
Y613255D01*
X293162Y618531D01*
Y641962D01*
X303000Y651800D01*
Y812000D01*
X327000Y836000D01*
Y846100D01*
X328750Y847850D01*
Y1157250D01*
X331500Y1160000D01*
Y1184800D01*
X329000Y1187300D01*
Y1195100D01*
X319100Y1205000D01*
Y1238100D01*
X325912Y1244912D01*
Y1353088D01*
X311500Y1367500D01*
Y1374500D01*
G01X512656Y623500D02*
X515137D01*
X515812Y622825D01*
Y620493D01*
X512119Y616800D01*
X497700D01*
X488312Y626188D01*
X314112D01*
X311100Y623176D01*
Y616570D01*
X310030Y615500D01*
G01X298030Y621000D02*
X298437Y621407D01*
Y621758D01*
X298900Y622221D01*
Y627976D01*
X306099Y635175D01*
X523301D01*
X565175Y593301D01*
Y531099D01*
X561276Y527200D01*
X555375D01*
X555000Y526825D01*
Y524344D01*
G01X520156Y623500D02*
X518662D01*
X517987Y622825D01*
Y619592D01*
X513020Y614625D01*
X496799D01*
X487411Y624013D01*
X315013D01*
X313275Y622275D01*
Y616058D01*
X313833Y615500D01*
G01X301833Y621000D02*
X301075Y621758D01*
Y627075D01*
X307000Y633000D01*
X522400D01*
X563000Y592400D01*
Y532000D01*
X560375Y529375D01*
X555525D01*
X555000Y529900D01*
Y531844D01*
G01X317156Y1193440D02*
X318840D01*
X319637Y1194237D01*
Y1197763D01*
X315400Y1202000D01*
X297000D01*
X288000Y1211000D01*
Y1379167D01*
X287167Y1380000D01*
G01X324656Y1193440D02*
X322560D01*
X321812Y1194188D01*
Y1198664D01*
X316301Y1204175D01*
X297901D01*
X290175Y1211901D01*
Y1379205D01*
X290970Y1380000D01*
G01X287167D02*
X288000Y1380833D01*
Y1392181D01*
X293507Y1397688D01*
X301007D01*
X316800Y1413481D01*
Y1501981D01*
X330225Y1515406D01*
Y1677299D01*
X320800Y1686724D01*
Y1689796D01*
X318156Y1692440D01*
G01X290970Y1380000D02*
X290175Y1380795D01*
Y1391280D01*
X294408Y1395513D01*
X301908D01*
X318975Y1412580D01*
Y1501080D01*
X332400Y1514505D01*
Y1678200D01*
X322975Y1687625D01*
Y1689759D01*
X325656Y1692440D01*
G01X311500Y1374500D02*
Y1377000D01*
X319500Y1385000D01*
Y1389000D01*
G01X376808Y1755434D02*
X375800Y1756442D01*
Y1760595D01*
X371420Y1764975D01*
X366699D01*
X359325Y1757601D01*
Y1745301D01*
X351985Y1737961D01*
X303785D01*
X285624Y1719800D01*
X276900D01*
X275575Y1721125D01*
Y1725319D01*
X276402Y1726146D01*
G01X373005Y1755434D02*
X373625Y1756054D01*
Y1759694D01*
X370519Y1762800D01*
X367600D01*
X361500Y1756700D01*
Y1744400D01*
X352886Y1735786D01*
X304686D01*
X286525Y1717625D01*
X275999D01*
X273400Y1720224D01*
Y1725345D01*
X272599Y1726146D01*
G01X360100Y808080D02*
X377580D01*
X390000Y820500D01*
G01D02*
X398000Y828500D01*
Y840000D01*
X402000Y844000D01*
G01X398750Y1188250D02*
X390140Y1179640D01*
X383140D01*
G01D02*
X359175D01*
G01X330300Y1411100D02*
X330302Y1411098D01*
Y1411050D01*
X330977Y1410375D01*
X344701D01*
X447175Y1307901D01*
Y1157599D01*
X422801Y1133225D01*
X412925D01*
X412500Y1132800D01*
Y1130750D01*
G01X330300Y1407297D02*
X331203Y1408200D01*
X343800D01*
X445000Y1307000D01*
Y1158500D01*
X421900Y1135400D01*
X412869D01*
X412500Y1135769D01*
Y1138250D01*
G01X358156Y1411000D02*
X356300D01*
X355400Y1411900D01*
Y1415495D01*
X348220Y1422675D01*
X330795D01*
X330000Y1423470D01*
G01X350656Y1411000D02*
X352600D01*
X353225Y1411625D01*
Y1414594D01*
X347319Y1420500D01*
X330833D01*
X330000Y1419667D01*
G01Y1435170D02*
X330695Y1434475D01*
X339399D01*
X444513Y1539589D01*
Y1745908D01*
X448280Y1749675D01*
X454220D01*
X455987Y1747908D01*
Y1743675D01*
X456662Y1743000D01*
X458156D01*
G01X330000Y1431367D02*
X330933Y1432300D01*
X340300D01*
X446688Y1538688D01*
Y1745007D01*
X449181Y1747500D01*
X453319D01*
X453812Y1747007D01*
Y1743675D01*
X453137Y1743000D01*
X450656D01*
G01X376890Y1678000D02*
X383000D01*
X395500Y1690500D01*
G01X379000Y1726000D02*
X395500Y1709500D01*
Y1703000D01*
G01D02*
Y1690500D01*
G01X427500Y297156D02*
X430344Y300000D01*
X444319D01*
X549819Y194500D01*
X791442D01*
X792343Y193599D01*
G01X427500Y304656D02*
X429981Y302175D01*
X445220D01*
X550720Y196675D01*
X791616D01*
X792343Y197402D01*
G01X973000Y1641500D02*
X985602D01*
X986000Y1641102D01*
X1008244D01*
G01X931000Y1671500D02*
Y1659000D01*
G01X979500Y1669750D02*
Y1667800D01*
X980213Y1667087D01*
X991387D01*
X995402Y1671102D01*
X1008244D01*
G01X979500Y1662250D02*
Y1664200D01*
X980212Y1664912D01*
X991413D01*
X995223Y1661102D01*
X1008244D01*
G01X930000Y1685000D02*
X926500Y1681500D01*
Y1660000D01*
G01X941000Y1653000D02*
X942898Y1651102D01*
X1008244D01*
G01X934825Y1682285D02*
X939500Y1686960D01*
Y1698000D01*
G54D15*
X37000Y762000D03*
X25000Y988000D03*
X27825Y995000D03*
X38800Y1810100D03*
X22100Y1802800D03*
X38317Y1804491D03*
X34900Y1807200D03*
X35100Y1813000D03*
X26500Y1805200D03*
X26600Y1810600D03*
X26300Y1815000D03*
X30800Y1805300D03*
Y1810500D03*
X17500Y1801900D03*
X22000Y1814100D03*
Y1809100D03*
X17500Y1806900D03*
Y1811900D03*
Y1816500D03*
X7600Y1855000D03*
X17500Y1827500D03*
X22600Y1825200D03*
X17500Y1832500D03*
X22500Y1830000D03*
X17500Y1837500D03*
X22500Y1835000D03*
X17500Y1842500D03*
X22500Y1840000D03*
X17500Y1847500D03*
X22500Y1845000D03*
X17500Y1852500D03*
X22500Y1850000D03*
X17500Y1857500D03*
X22500Y1855000D03*
Y1865000D03*
X17500Y1867500D03*
X22500Y1860000D03*
X12500Y1845000D03*
Y1850000D03*
Y1855000D03*
Y1840000D03*
X17500Y1872500D03*
X22500Y1870000D03*
X12500D03*
X71200Y36900D03*
X105750Y217750D03*
X73900Y269500D03*
X78675Y380704D03*
X47500Y660500D03*
X80100Y805500D03*
X80215Y787900D03*
X43387Y803500D03*
X40087Y788400D03*
X41000Y908000D03*
X56000Y967000D03*
X45000Y1057000D03*
X81175Y1066404D03*
X51944Y1232506D03*
X79390Y1327082D03*
X65000Y1336000D03*
X50100Y1317400D03*
X94642Y1456100D03*
X77607Y1565391D03*
X55738Y1578587D03*
X58777Y1585826D03*
X49555Y1583740D03*
X45402Y1712309D03*
X45150Y1720650D03*
X55500Y1763000D03*
X83600Y1736600D03*
X53200Y1865800D03*
X63579Y1894881D03*
X70650Y1897792D03*
X50100Y1872800D03*
X136100Y41200D03*
X183344Y808200D03*
X126221Y861250D03*
Y853750D03*
X148000Y966500D03*
X142066Y958234D03*
X141250Y978050D03*
X132000Y1042000D03*
X112700Y1079600D03*
X163170Y1210999D03*
X162500Y1380500D03*
X117387Y1536250D03*
Y1543750D03*
X122844Y1672400D03*
X130344D03*
X122000Y1727500D03*
X147200Y1756600D03*
X157900Y1770500D03*
X213244Y23725D03*
X243156Y382060D03*
X235656D03*
X228156Y438500D03*
X220656D03*
X206700Y575000D03*
X190844Y808200D03*
X242700Y1266656D03*
Y1259156D03*
X243590Y1779507D03*
X232344Y1740000D03*
X239844D03*
X320700Y396100D03*
X318700Y469800D03*
X328250Y441400D03*
X284000Y541344D03*
Y548844D03*
X318800Y823700D03*
X317156Y1193440D03*
X324656D03*
X276344Y1183060D03*
X268844D03*
X328250Y1233000D03*
X311500Y1374500D03*
X401500Y395500D03*
X393500Y422000D03*
X401500Y830000D03*
X390000Y820500D03*
X393500Y852000D03*
X402000Y1196500D03*
X396637Y1176000D03*
X383140Y1179640D03*
X358156Y1411000D03*
X350656D03*
X402000Y1695000D03*
X379500Y1673750D03*
X335025Y1701725D03*
X395500Y1703000D03*
X427500Y297156D03*
Y304656D03*
X412500Y1130750D03*
Y1138250D03*
X438656Y1669000D03*
X431156D03*
X458156Y1743000D03*
X450656D03*
X512656Y623500D03*
X520156D03*
X555000Y524344D03*
Y531844D03*
X689000Y1592500D03*
X719901Y939198D03*
X740464Y1499388D03*
X698500Y1812000D03*
X807756Y377775D03*
X808256Y783275D03*
X807756Y1188775D03*
X831000Y1625000D03*
X807756Y1594275D03*
X851000Y1627000D03*
X903500Y1627500D03*
X873500Y1625500D03*
X935000Y1425000D03*
X984900Y1430400D03*
X953800Y1424900D03*
X945000Y1425000D03*
X975000D03*
X935000Y1455000D03*
Y1475000D03*
Y1445000D03*
Y1465000D03*
Y1435000D03*
X945000Y1475000D03*
X955000D03*
X965000D03*
X945000Y1465000D03*
X955000D03*
X965000D03*
X945000Y1455000D03*
X955000D03*
X965000D03*
X945000Y1445000D03*
X955000D03*
X965000D03*
X945000Y1435000D03*
X955000D03*
X965000D03*
Y1495000D03*
X955000D03*
X935000Y1485000D03*
Y1495000D03*
X945000D03*
Y1485000D03*
X955000D03*
X965000D03*
X975000Y1495000D03*
Y1485000D03*
Y1475000D03*
Y1465000D03*
Y1455000D03*
Y1445000D03*
Y1435000D03*
X950000Y1440000D03*
X960000Y1460000D03*
X950000Y1470000D03*
Y1500000D03*
X965000Y1525000D03*
X955000D03*
X945000D03*
Y1516000D03*
X955000D03*
X965000D03*
X935000Y1555000D03*
X945000D03*
X955000D03*
X965000D03*
X935000Y1575000D03*
Y1565000D03*
X945000Y1575000D03*
X955000D03*
X965000D03*
Y1565000D03*
X955000D03*
X945000D03*
X935000Y1545000D03*
Y1535000D03*
Y1525000D03*
Y1516000D03*
X965000Y1545000D03*
X955000D03*
X945000D03*
Y1535000D03*
X955000D03*
X965000D03*
X975000Y1565000D03*
Y1575000D03*
Y1525000D03*
Y1535000D03*
Y1545000D03*
Y1555000D03*
X960000Y1540000D03*
X950000Y1550000D03*
X940000Y1570000D03*
X935000Y1505000D03*
X955000D03*
X945000D03*
X965000D03*
Y1605000D03*
X935000Y1595000D03*
Y1585000D03*
X945000Y1595000D03*
X955000D03*
X965000D03*
Y1585000D03*
X955000D03*
X945000D03*
X975000Y1595000D03*
Y1605000D03*
Y1585000D03*
X940000Y1605000D03*
X933500Y1625000D03*
X961500Y1624500D03*
X931000Y1671500D03*
X979500Y1669750D03*
Y1662250D03*
X930000Y1685000D03*
X939500Y1698000D03*
X913000Y1717750D03*
X990600Y1427100D03*
X995000Y1425000D03*
X1005000D03*
G54D25*
G01X7358Y607646D02*
X14402D01*
X15376Y608620D01*
X19000D01*
X20000Y607620D01*
G01X7358Y610796D02*
X14401D01*
X15376Y609821D01*
X19001D01*
X20000Y610820D01*
G01X7358Y620245D02*
X14402D01*
X15376Y621219D01*
X18999D01*
X20000Y620218D01*
G01X7358Y623394D02*
X14402D01*
X15376Y622420D01*
X19002D01*
X20000Y623418D01*
G01X7358Y658040D02*
X14402D01*
X15376Y659014D01*
X18999D01*
X20000Y658013D01*
G01X7358Y661189D02*
X14402D01*
X15376Y660215D01*
X19002D01*
X20000Y661213D01*
G01X7358Y670638D02*
X14402D01*
X15376Y671612D01*
X19000D01*
X20000Y670612D01*
G01X7358Y673788D02*
X14401D01*
X15376Y672813D01*
X19001D01*
X20000Y673812D01*
G01X7358Y683237D02*
X14402D01*
X15376Y684211D01*
X18999D01*
X20000Y683210D01*
G01X7358Y686386D02*
X14402D01*
X15376Y685412D01*
X19002D01*
X20000Y686410D01*
G01X7358Y632843D02*
X14402D01*
X15376Y633817D01*
X19000D01*
X20000Y632817D01*
G01X7358Y635993D02*
X14401D01*
X15376Y635018D01*
X19001D01*
X20000Y636017D01*
G01X7358Y695835D02*
X14402D01*
X15376Y696809D01*
X19000D01*
X20000Y695809D01*
G01X7358Y698985D02*
X14401D01*
X15376Y698010D01*
X19001D01*
X20000Y699009D01*
G01X7358Y645441D02*
X14402D01*
X15376Y646415D01*
X19000D01*
X20000Y645415D01*
G01X7358Y648591D02*
X14401D01*
X15376Y647616D01*
X19001D01*
X20000Y648615D01*
G01X7358Y708433D02*
X14402D01*
X15376Y709407D01*
X19000D01*
X20000Y708407D01*
G01X7358Y711583D02*
X14401D01*
X15376Y710608D01*
X19001D01*
X20000Y711607D01*
G01X7358Y721032D02*
X14402D01*
X15376Y722006D01*
X19000D01*
X20000Y721006D01*
G01X7358Y724182D02*
X14401D01*
X15376Y723207D01*
X19001D01*
X20000Y724206D01*
G01X7358Y752528D02*
X14402D01*
X15376Y753502D01*
X19000D01*
X20000Y752502D01*
G01X7358Y755678D02*
X14401D01*
X15376Y754703D01*
X19001D01*
X20000Y755702D01*
G01X7358Y765126D02*
X14402D01*
X15376Y766100D01*
X19000D01*
X20000Y765100D01*
G01X7358Y768276D02*
X14401D01*
X15376Y767301D01*
X19001D01*
X20000Y768300D01*
G01X7358Y837567D02*
X14402D01*
X15770Y838541D01*
X19000D01*
X20000Y837541D01*
G01X7358Y840717D02*
X14743D01*
X15718Y839742D01*
X19001D01*
X20000Y840741D01*
G01X7358Y787174D02*
X14402D01*
X15376Y788148D01*
X18999D01*
X20000Y787147D01*
G01X7358Y790323D02*
X14402D01*
X15376Y789349D01*
X19002D01*
X20000Y790347D01*
G01X7358Y799772D02*
X14402D01*
X15376Y800746D01*
X19000D01*
X20000Y799746D01*
G01X7358Y802922D02*
X14401D01*
X15376Y801947D01*
X19001D01*
X20000Y802946D01*
G01X7358Y812371D02*
X14402D01*
X15376Y813345D01*
X18999D01*
X20000Y812344D01*
G01X7358Y815520D02*
X14402D01*
X15376Y814546D01*
X19002D01*
X20000Y815544D01*
G01X7358Y824969D02*
X14402D01*
X15376Y825943D01*
X19000D01*
X20000Y824943D01*
G01X7358Y828119D02*
X14401D01*
X15376Y827144D01*
X19001D01*
X20000Y828143D01*
G01X7358Y900559D02*
X14402D01*
X15376Y901533D01*
X19000D01*
X20000Y900533D01*
G01X7358Y903709D02*
X14401D01*
X15376Y902734D01*
X19001D01*
X20000Y903733D01*
G01X7358Y850166D02*
X14402D01*
X15880Y851140D01*
X18999D01*
X20000Y850139D01*
G01X7358Y853315D02*
X14895D01*
X15869Y852341D01*
X19002D01*
X20000Y853339D01*
G01X7358Y913158D02*
X14402D01*
X15376Y914132D01*
X19000D01*
X20000Y913132D01*
G01X7358Y916308D02*
X14401D01*
X15376Y915333D01*
X19001D01*
X20000Y916332D01*
G01X7358Y862764D02*
X14417D01*
X15801Y863738D01*
X19000D01*
X20000Y862738D01*
G01X7358Y865914D02*
X14876D01*
X15851Y864939D01*
X19001D01*
X20000Y865938D01*
G01X7358Y875363D02*
X14402D01*
X15376Y876337D01*
X18999D01*
X20000Y875336D01*
G01X7358Y878512D02*
X14402D01*
X15376Y877538D01*
X19002D01*
X20000Y878536D01*
G01X7358Y1103709D02*
X14402D01*
X15376Y1104683D01*
X19000D01*
X20000Y1103683D01*
G01X7358Y1106859D02*
X14401D01*
X15376Y1105884D01*
X19001D01*
X20000Y1106883D01*
G01X7358Y1116308D02*
X14402D01*
X15376Y1117282D01*
X18999D01*
X20000Y1116281D01*
G01X7358Y1119457D02*
X14402D01*
X15376Y1118483D01*
X19002D01*
X20000Y1119481D01*
G01X7358Y1141504D02*
X14402D01*
X15376Y1142478D01*
X19000D01*
X20000Y1141478D01*
G01X7358Y1144654D02*
X14401D01*
X15376Y1143679D01*
X19001D01*
X20000Y1144678D01*
G01X7358Y1191898D02*
X14402D01*
X15376Y1192872D01*
X19000D01*
X20000Y1191872D01*
G01X7358Y1195048D02*
X14401D01*
X15376Y1194073D01*
X19001D01*
X20000Y1195072D01*
G01X7358Y1154103D02*
X14402D01*
X15376Y1155077D01*
X18999D01*
X20000Y1154076D01*
G01X7358Y1157252D02*
X14402D01*
X15376Y1156278D01*
X19002D01*
X20000Y1157276D01*
G01X7358Y1204496D02*
X14402D01*
X15376Y1205470D01*
X19000D01*
X20000Y1204470D01*
G01X7358Y1207646D02*
X14401D01*
X15376Y1206671D01*
X19001D01*
X20000Y1207670D01*
G01X7358Y1166701D02*
X14402D01*
X15376Y1167675D01*
X19000D01*
X20000Y1166675D01*
G01X7358Y1169851D02*
X14401D01*
X15376Y1168876D01*
X19001D01*
X20000Y1169875D01*
G01X7358Y1179300D02*
X14402D01*
X15376Y1180274D01*
X18999D01*
X20000Y1179273D01*
G01X7358Y1182449D02*
X14402D01*
X15376Y1181475D01*
X19002D01*
X20000Y1182473D01*
G01X7358Y1261189D02*
X14402D01*
X15376Y1262163D01*
X19000D01*
X20000Y1261163D01*
G01X7358Y1264339D02*
X14401D01*
X15376Y1263364D01*
X19001D01*
X20000Y1264363D01*
G01X7358Y1273788D02*
X14402D01*
X15376Y1274762D01*
X18999D01*
X20000Y1273761D01*
G01X7358Y1276937D02*
X14402D01*
X15376Y1275963D01*
X19002D01*
X20000Y1276961D01*
G01X7358Y1217095D02*
X14402D01*
X15376Y1218069D01*
X19000D01*
X20000Y1217069D01*
G01X7358Y1220245D02*
X14401D01*
X15376Y1219270D01*
X19001D01*
X20000Y1220269D01*
G01X7358Y1248591D02*
X14402D01*
X15376Y1249565D01*
X19000D01*
X20000Y1248565D01*
G01X7358Y1251741D02*
X14401D01*
X15376Y1250766D01*
X19001D01*
X20000Y1251765D01*
G01X7358Y1321032D02*
X14402D01*
X15376Y1322006D01*
X19000D01*
X20000Y1321006D01*
G01X7358Y1324182D02*
X14401D01*
X15376Y1323207D01*
X19001D01*
X20000Y1324206D01*
G01X7358Y1333630D02*
X14402D01*
X15376Y1334604D01*
X19000D01*
X20000Y1333604D01*
G01X7358Y1336780D02*
X14401D01*
X15376Y1335805D01*
X19001D01*
X20000Y1336804D01*
G01X7358Y1346229D02*
X14402D01*
X15376Y1347203D01*
X18999D01*
X20000Y1346202D01*
G01X7358Y1349378D02*
X14402D01*
X15790Y1348404D01*
X19002D01*
X20000Y1349402D01*
G01X7358Y1286386D02*
X14402D01*
X15376Y1287360D01*
X19000D01*
X20000Y1286360D01*
G01X7358Y1289536D02*
X14401D01*
X15376Y1288561D01*
X19001D01*
X20000Y1289560D01*
G01X7358Y1298985D02*
X14402D01*
X15376Y1299959D01*
X18999D01*
X20000Y1298958D01*
G01X7358Y1302134D02*
X14402D01*
X15376Y1301160D01*
X19002D01*
X20000Y1302158D01*
G01X7358Y1371426D02*
X14402D01*
X15376Y1372400D01*
X18999D01*
X20000Y1371399D01*
G01X7358Y1374575D02*
X14402D01*
X15376Y1373601D01*
X19002D01*
X20000Y1374599D01*
G01X7358Y1384024D02*
X14402D01*
X15376Y1384998D01*
X19000D01*
X20000Y1383998D01*
G01X7358Y1387174D02*
X14401D01*
X15376Y1386199D01*
X19001D01*
X20000Y1387198D01*
G01X7358Y1396622D02*
X14402D01*
X15376Y1397596D01*
X19000D01*
X20000Y1396596D01*
G01X7358Y1399772D02*
X14401D01*
X15376Y1398797D01*
X19001D01*
X20000Y1399796D01*
G01X7358Y1358827D02*
X14377D01*
X15351Y1359801D01*
X19000D01*
X20000Y1358801D01*
G01X7358Y1361977D02*
X14401D01*
X15770Y1361002D01*
X19001D01*
X20000Y1362001D01*
G01X7358Y1409221D02*
X14402D01*
X15376Y1410195D01*
X19000D01*
X20000Y1409195D01*
G01X7358Y1412371D02*
X14401D01*
X15376Y1411396D01*
X19001D01*
X20000Y1412395D01*
G01X7358Y1530480D02*
X14402D01*
X15376Y1531454D01*
X19000D01*
X20000Y1530454D01*
G01X7358Y1533630D02*
X14401D01*
X15376Y1532655D01*
X19001D01*
X20000Y1533654D01*
G01X7358Y1543078D02*
X14402D01*
X15376Y1544052D01*
X19000D01*
X20000Y1543052D01*
G01X7358Y1546228D02*
X14401D01*
X15376Y1545253D01*
X19001D01*
X20000Y1546252D01*
G01X7358Y1555677D02*
X14401D01*
X15375Y1556651D01*
X18999D01*
X20000Y1555650D01*
G01X7358Y1558826D02*
X14401D01*
X15375Y1557852D01*
X19002D01*
X20000Y1558850D01*
G01X7358Y1568275D02*
X14402D01*
X15376Y1569249D01*
X19000D01*
X20000Y1568249D01*
G01X7358Y1571425D02*
X14401D01*
X15376Y1570450D01*
X19001D01*
X20000Y1571449D01*
G01X33001Y1518123D02*
X34000Y1517124D01*
Y1514583D01*
X33417Y1514000D01*
X31768D01*
X31225Y1514543D01*
X29241D01*
X28698Y1514000D01*
X26634D01*
X26037Y1514597D01*
X24161D01*
X23564Y1514000D01*
X21499D01*
X19406Y1516093D01*
X15439D01*
X14965Y1516567D01*
Y1517317D01*
X14401Y1517881D01*
X7358D01*
G01X36201Y1518123D02*
X35201Y1517123D01*
Y1514085D01*
X33915Y1512799D01*
X21001D01*
X18908Y1514892D01*
X15153D01*
X14993Y1514732D01*
X7358D01*
G01Y1640716D02*
X14402D01*
X15376Y1641690D01*
X19000D01*
X20000Y1640690D01*
G01X7358Y1643866D02*
X14401D01*
X15376Y1642891D01*
X19001D01*
X20000Y1643890D01*
G01X7358Y1593472D02*
X14401D01*
X15376Y1592497D01*
X19001D01*
X20000Y1593496D01*
G01X7358Y1590322D02*
X14402D01*
X15376Y1591296D01*
X19000D01*
X20000Y1590296D01*
G01X7358Y1606070D02*
X14401D01*
X15375Y1605096D01*
X19002D01*
X20000Y1606094D01*
G01X7358Y1602921D02*
X14401D01*
X15375Y1603895D01*
X18999D01*
X20000Y1602894D01*
G01X7358Y1618669D02*
X14401D01*
X15376Y1617694D01*
X19001D01*
X20000Y1618693D01*
G01X7358Y1615519D02*
X14402D01*
X15376Y1616493D01*
X19000D01*
X20000Y1615493D01*
G01X7358Y1631267D02*
X14401D01*
X15375Y1630293D01*
X19002D01*
X20000Y1631291D01*
G01X7358Y1628118D02*
X14401D01*
X15375Y1629092D01*
X18999D01*
X20000Y1628091D01*
G01X7358Y1716307D02*
X14402D01*
X15376Y1715333D01*
X19002D01*
X20000Y1716331D01*
G01X7358Y1713157D02*
X14401D01*
X15376Y1714132D01*
X18999D01*
X20000Y1713131D01*
G01X7358Y1665913D02*
X14401D01*
X15376Y1666888D01*
X18999D01*
X20000Y1665887D01*
G01X7358Y1669063D02*
X14402D01*
X15376Y1668089D01*
X19002D01*
X20000Y1669087D01*
G01X7358Y1678511D02*
X14401D01*
X15376Y1679486D01*
X18999D01*
X20000Y1678485D01*
G01X7358Y1681661D02*
X14402D01*
X15376Y1680687D01*
X19002D01*
X20000Y1681685D01*
G01X7358Y1691110D02*
X14401D01*
X15375Y1692084D01*
X18999D01*
X20000Y1691083D01*
G01X7358Y1694259D02*
X14401D01*
X15375Y1693285D01*
X19002D01*
X20000Y1694283D01*
G01X7358Y1728905D02*
X14401D01*
X15375Y1727931D01*
X19002D01*
X20000Y1728929D01*
G01X7358Y1725756D02*
X14401D01*
X15375Y1726730D01*
X18999D01*
X20000Y1725729D01*
G01X7358Y1741504D02*
X14402D01*
X15376Y1740530D01*
X19002D01*
X20000Y1741528D01*
G01X7358Y1738354D02*
X14401D01*
X15376Y1739329D01*
X18999D01*
X20000Y1738328D01*
G01X7358Y1754102D02*
X14401D01*
X15377Y1753126D01*
X19000D01*
X20000Y1754126D01*
G01X7358Y1750952D02*
X14402D01*
X15375Y1751925D01*
X19001D01*
X20000Y1750926D01*
G01X7358Y1763551D02*
X14401D01*
X15376Y1762576D01*
X18877D01*
X21801Y1765500D01*
X25500D01*
X26500Y1766500D01*
Y1768558D01*
X25500Y1769558D01*
G01X7358Y1760401D02*
X14402D01*
X15376Y1761375D01*
X19375D01*
X22299Y1764299D01*
X25998D01*
X27701Y1766002D01*
Y1768559D01*
X28700Y1769558D01*
G01X68000Y128359D02*
X68999Y129358D01*
X123001D01*
X124000Y128359D01*
G01X68000Y131559D02*
X69000Y130559D01*
X123000D01*
X124000Y131559D01*
G01X68000Y533871D02*
X69001Y534872D01*
X123001D01*
X124000Y533873D01*
G01Y537073D02*
X123000Y536073D01*
X68998D01*
X68000Y537071D01*
G01X167000Y939309D02*
X166001Y940308D01*
X142104D01*
X141601Y939805D01*
X139537D01*
X139034Y940308D01*
X136970D01*
X136467Y939805D01*
X134403D01*
X133900Y940308D01*
X123900D01*
X123397Y939805D01*
X121333D01*
X120830Y940308D01*
X118766D01*
X118263Y939805D01*
X116199D01*
X115696Y940308D01*
X113632D01*
X113129Y939805D01*
X111065D01*
X110562Y940308D01*
X68925D01*
X68000Y939383D01*
G01Y942583D02*
X69074Y941509D01*
X166000D01*
X167000Y942509D01*
G01X68000Y1344895D02*
X68925Y1345820D01*
X128501D01*
X129500Y1344821D01*
G01X68000Y1348095D02*
X69074Y1347021D01*
X128500D01*
X129500Y1348021D01*
G01X68000Y1750407D02*
X68926Y1751333D01*
X124001D01*
X125000Y1750334D01*
G01X68000Y1753607D02*
X69073Y1752534D01*
X124000D01*
X125000Y1753534D01*
G01X190500Y238501D02*
X189501Y239500D01*
X180000D01*
X179000Y238500D01*
Y236394D01*
X180000Y235394D01*
G01X190500Y241701D02*
X189500Y240701D01*
X179502D01*
X177799Y238998D01*
Y236393D01*
X176800Y235394D01*
G01X190500Y644013D02*
X189501Y645012D01*
X180000D01*
X179000Y644012D01*
Y641906D01*
X180000Y640906D01*
G01X190500Y647213D02*
X189500Y646213D01*
X179502D01*
X177799Y644510D01*
Y641905D01*
X176800Y640906D01*
G01X180000Y1046418D02*
X179000Y1047418D01*
Y1049524D01*
X180000Y1050524D01*
X189501D01*
X190500Y1049525D01*
G01X176800Y1046418D02*
X177799Y1047417D01*
Y1050022D01*
X179502Y1051725D01*
X189500D01*
X190500Y1052725D01*
G01Y1455037D02*
X189501Y1456036D01*
X180000D01*
X179000Y1455036D01*
Y1452930D01*
X180000Y1451930D01*
G01X190500Y1458237D02*
X189500Y1457237D01*
X179502D01*
X177799Y1455534D01*
Y1452929D01*
X176800Y1451930D01*
G01X180000Y1857442D02*
X179000Y1858442D01*
Y1860548D01*
X180000Y1861548D01*
X189501D01*
X190500Y1860549D01*
G01X176800Y1857442D02*
X177799Y1858441D01*
Y1861046D01*
X179502Y1862749D01*
X189500D01*
X190500Y1863749D01*
G01X295600Y1693400D02*
X294600Y1694400D01*
Y1697500D01*
X292500Y1699600D01*
X286000D01*
X285000Y1700600D01*
G01X292400Y1693400D02*
X293399Y1694399D01*
Y1697002D01*
X292002Y1698399D01*
X285999D01*
X285000Y1697400D01*
G01X908346Y235394D02*
X907346Y236394D01*
Y238500D01*
X908346Y239500D01*
X917847D01*
X918846Y238501D01*
G01X905146Y235394D02*
X906145Y236393D01*
Y238998D01*
X907848Y240701D01*
X917846D01*
X918846Y241701D01*
G01Y644013D02*
X917847Y645012D01*
X908346D01*
X907346Y644012D01*
Y641906D01*
X908346Y640906D01*
G01X918846Y647213D02*
X917846Y646213D01*
X907848D01*
X906145Y644510D01*
Y641905D01*
X905146Y640906D01*
G01X918846Y1049525D02*
X917847Y1050524D01*
X908346D01*
X907346Y1049524D01*
Y1047418D01*
X908346Y1046418D01*
G01X918846Y1052725D02*
X917846Y1051725D01*
X907848D01*
X906145Y1050022D01*
Y1047417D01*
X905146Y1046418D01*
G01X918846Y1455037D02*
X917847Y1456036D01*
X908346D01*
X907346Y1455036D01*
Y1452930D01*
X908346Y1451930D01*
G01X918846Y1458237D02*
X917846Y1457237D01*
X907848D01*
X906145Y1455534D01*
Y1452929D01*
X905146Y1451930D01*
G01X918846Y1860549D02*
X917847Y1861548D01*
X908346D01*
X907346Y1860548D01*
Y1858442D01*
X908346Y1857442D01*
G01X918846Y1863749D02*
X917846Y1862749D01*
X907848D01*
X906145Y1861046D01*
Y1858441D01*
X905146Y1857442D01*
G54D16*
X33469Y1029523D03*
X269690Y1490152D03*
G54D17*
X72835Y17047D03*
Y190275D03*
Y422559D03*
Y595787D03*
Y828071D03*
Y1001299D03*
Y1233583D03*
Y1406811D03*
Y1639095D03*
Y1812323D03*
X171260Y179803D03*
Y353031D03*
Y585315D03*
Y758543D03*
Y990827D03*
Y1164055D03*
Y1396339D03*
Y1569567D03*
Y1801851D03*
Y1975079D03*
X899606Y179803D03*
Y353031D03*
Y585315D03*
Y758543D03*
Y990827D03*
Y1164055D03*
Y1396339D03*
Y1569567D03*
Y1801851D03*
Y1975079D03*
G54D18*
X1001545Y1492322D03*
Y1452322D03*
Y1572322D03*
Y1532322D03*
G54D19*
X1001544Y1602322D03*
M02*
